FILE_TYPE = MACRO_DRAWING;
SET COLOR_WIRE YELLOW;
SET COLOR_PROP MONO;
SET COLOR_DOT WHITE;
SET COLOR_ARC YELLOW;
SET COLOR_BODY GREEN;
SET COLOR_NOTE MONO;
SET PROP_DISPLAY VALUE;
SET PAGE_NUMBER P27;
FORCEADD OFFPAGE..5
(-6450 500);
FORCEPROP 2 LAST $XR1 52 
J 0
(-6764 500);
DISPLAY 0.638298 (-6764 500);
PAINT MONO (-6764 500);
FORCEPROP 2 LAST $XR0 51 
J 0
(-6674 500);
DISPLAY 0.638298 (-6674 500);
PAINT MONO (-6674 500);
FORCEPROP 2 LAST CDS_LIB mstr_standard
J 0
(-6450 500);
PAINT MONO (-6450 500);
DISPLAY INVISIBLE (-6450 500);
FORCEPROP 1 LAST OFFPAGE TRUE
J 0
(-6125 375);
DISPLAY 1.170213 (-6125 375);
PAINT GREEN (-6125 375);
DISPLAY INVISIBLE (-6125 375);
FORCEPROP 1 LAST COMMENT_BODY TRUE
J 0
(-6350 425);
DISPLAY 1.170213 (-6350 425);
PAINT GREEN (-6350 425);
DISPLAY INVISIBLE (-6350 425);
FORCEPROP 2 LAST PATH I1
J 0
(-6400 575);
DISPLAY 1.021277 (-6400 575);
PAINT ORANGE (-6400 575);
DISPLAY INVISIBLE (-6400 575);
FORCEADD TAP..6
(-5575 850);
FORCEPROP 3 LASTPIN (-5525 850) SIG_NAME M_E_CLK_DP<1>
J 0
(-5515 860);
DISPLAY 0.659574 (-5515 860);
PAINT MONO (-5515 860);
DISPLAY INVISIBLE (-5515 860);
FORCEPROP 1 LASTPIN (-5525 850) BN 1
J 0
(-5577 858);
DISPLAY 0.617021 (-5577 858);
PAINT PINK (-5577 858);
FORCEPROP 2 LAST CDS_LIB mstr_standard
J 0
(-5575 850);
PAINT MONO (-5575 850);
DISPLAY INVISIBLE (-5575 850);
FORCEPROP 1 LAST BODY_TYPE PLUMBING
J 0
(-5575 800);
DISPLAY 1.595745 (-5575 800);
PAINT GREEN (-5575 800);
DISPLAY INVISIBLE (-5575 800);
FORCEPROP 1 LAST HDL_TAP TRUE
J 0
(-5250 725);
DISPLAY 1.595745 (-5250 725);
PAINT GREEN (-5250 725);
DISPLAY INVISIBLE (-5250 725);
FORCEPROP 1 LAST PATH I10
J 0
(-5577 850);
DISPLAY 0.872340 (-5577 850);
PAINT GREEN (-5577 850);
DISPLAY INVISIBLE (-5577 850);
FORCEADD TAP..6
R 2
(-2850 1400);
FORCEPROP 3 LASTPIN (-2900 1400) SIG_NAME M_E_ODT<0>
J 0
(-2890 1410);
DISPLAY 0.659574 (-2890 1410);
PAINT MONO (-2890 1410);
DISPLAY INVISIBLE (-2890 1410);
FORCEPROP 1 LASTPIN (-2900 1400) BN 0
J 2
(-2848 1408);
DISPLAY 0.617021 (-2848 1408);
PAINT PINK (-2848 1408);
FORCEPROP 2 LAST CDS_LIB mstr_standard
J 0
(-2850 1400);
PAINT MONO (-2850 1400);
DISPLAY INVISIBLE (-2850 1400);
FORCEPROP 1 LAST BODY_TYPE PLUMBING
J 2
(-2850 1350);
DISPLAY 1.595745 (-2850 1350);
PAINT GREEN (-2850 1350);
DISPLAY INVISIBLE (-2850 1350);
FORCEPROP 1 LAST HDL_TAP TRUE
J 2
(-3175 1275);
DISPLAY 1.595745 (-3175 1275);
PAINT GREEN (-3175 1275);
DISPLAY INVISIBLE (-3175 1275);
FORCEPROP 1 LAST PATH I100
J 2
(-2848 1400);
DISPLAY 0.872340 (-2848 1400);
PAINT GREEN (-2848 1400);
DISPLAY INVISIBLE (-2848 1400);
FORCEADD TAP..6
R 2
(-2850 1550);
FORCEPROP 3 LASTPIN (-2900 1550) SIG_NAME M_E_ODT<3>
J 0
(-2890 1560);
DISPLAY 0.659574 (-2890 1560);
PAINT MONO (-2890 1560);
DISPLAY INVISIBLE (-2890 1560);
FORCEPROP 1 LASTPIN (-2900 1550) BN 3
J 2
(-2848 1558);
DISPLAY 0.617021 (-2848 1558);
PAINT PINK (-2848 1558);
FORCEPROP 2 LAST CDS_LIB mstr_standard
J 0
(-2850 1550);
PAINT MONO (-2850 1550);
DISPLAY INVISIBLE (-2850 1550);
FORCEPROP 1 LAST BODY_TYPE PLUMBING
J 2
(-2850 1500);
DISPLAY 1.595745 (-2850 1500);
PAINT GREEN (-2850 1500);
DISPLAY INVISIBLE (-2850 1500);
FORCEPROP 1 LAST HDL_TAP TRUE
J 2
(-3175 1425);
DISPLAY 1.595745 (-3175 1425);
PAINT GREEN (-3175 1425);
DISPLAY INVISIBLE (-3175 1425);
FORCEPROP 1 LAST PATH I101
J 2
(-2848 1550);
DISPLAY 0.872340 (-2848 1550);
PAINT GREEN (-2848 1550);
DISPLAY INVISIBLE (-2848 1550);
FORCEADD TAP..6
R 2
(-2850 1500);
FORCEPROP 3 LASTPIN (-2900 1500) SIG_NAME M_E_ODT<2>
J 0
(-2890 1510);
DISPLAY 0.659574 (-2890 1510);
PAINT MONO (-2890 1510);
DISPLAY INVISIBLE (-2890 1510);
FORCEPROP 1 LASTPIN (-2900 1500) BN 2
J 2
(-2848 1508);
DISPLAY 0.617021 (-2848 1508);
PAINT PINK (-2848 1508);
FORCEPROP 2 LAST CDS_LIB mstr_standard
J 0
(-2850 1500);
PAINT MONO (-2850 1500);
DISPLAY INVISIBLE (-2850 1500);
FORCEPROP 1 LAST BODY_TYPE PLUMBING
J 2
(-2850 1450);
DISPLAY 1.595745 (-2850 1450);
PAINT GREEN (-2850 1450);
DISPLAY INVISIBLE (-2850 1450);
FORCEPROP 1 LAST HDL_TAP TRUE
J 2
(-3175 1375);
DISPLAY 1.595745 (-3175 1375);
PAINT GREEN (-3175 1375);
DISPLAY INVISIBLE (-3175 1375);
FORCEPROP 1 LAST PATH I102
J 2
(-2848 1500);
DISPLAY 0.872340 (-2848 1500);
PAINT GREEN (-2848 1500);
DISPLAY INVISIBLE (-2848 1500);
FORCEADD TAP..6
R 2
(-2850 1650);
FORCEPROP 3 LASTPIN (-2900 1650) SIG_NAME M_E_CKE<0>
J 0
(-2890 1660);
DISPLAY 0.659574 (-2890 1660);
PAINT MONO (-2890 1660);
DISPLAY INVISIBLE (-2890 1660);
FORCEPROP 1 LASTPIN (-2900 1650) BN 0
J 2
(-2848 1658);
DISPLAY 0.617021 (-2848 1658);
PAINT PINK (-2848 1658);
FORCEPROP 2 LAST CDS_LIB mstr_standard
J 0
(-2850 1650);
PAINT MONO (-2850 1650);
DISPLAY INVISIBLE (-2850 1650);
FORCEPROP 1 LAST BODY_TYPE PLUMBING
J 2
(-2850 1600);
DISPLAY 1.595745 (-2850 1600);
PAINT GREEN (-2850 1600);
DISPLAY INVISIBLE (-2850 1600);
FORCEPROP 1 LAST HDL_TAP TRUE
J 2
(-3175 1525);
DISPLAY 1.595745 (-3175 1525);
PAINT GREEN (-3175 1525);
DISPLAY INVISIBLE (-3175 1525);
FORCEPROP 1 LAST PATH I103
J 2
(-2848 1650);
DISPLAY 0.872340 (-2848 1650);
PAINT GREEN (-2848 1650);
DISPLAY INVISIBLE (-2848 1650);
FORCEADD TAP..6
R 2
(-2850 1700);
FORCEPROP 3 LASTPIN (-2900 1700) SIG_NAME M_E_CKE<1>
J 0
(-2890 1710);
DISPLAY 0.659574 (-2890 1710);
PAINT MONO (-2890 1710);
DISPLAY INVISIBLE (-2890 1710);
FORCEPROP 1 LASTPIN (-2900 1700) BN 1
J 2
(-2848 1708);
DISPLAY 0.617021 (-2848 1708);
PAINT PINK (-2848 1708);
FORCEPROP 2 LAST CDS_LIB mstr_standard
J 0
(-2850 1700);
PAINT MONO (-2850 1700);
DISPLAY INVISIBLE (-2850 1700);
FORCEPROP 1 LAST BODY_TYPE PLUMBING
J 2
(-2850 1650);
DISPLAY 1.595745 (-2850 1650);
PAINT GREEN (-2850 1650);
DISPLAY INVISIBLE (-2850 1650);
FORCEPROP 1 LAST HDL_TAP TRUE
J 2
(-3175 1575);
DISPLAY 1.595745 (-3175 1575);
PAINT GREEN (-3175 1575);
DISPLAY INVISIBLE (-3175 1575);
FORCEPROP 1 LAST PATH I104
J 2
(-2848 1700);
DISPLAY 0.872340 (-2848 1700);
PAINT GREEN (-2848 1700);
DISPLAY INVISIBLE (-2848 1700);
FORCEADD TAP..6
R 2
(-2850 1800);
FORCEPROP 3 LASTPIN (-2900 1800) SIG_NAME M_E_CKE<3>
J 0
(-2890 1810);
DISPLAY 0.659574 (-2890 1810);
PAINT MONO (-2890 1810);
DISPLAY INVISIBLE (-2890 1810);
FORCEPROP 1 LASTPIN (-2900 1800) BN 3
J 2
(-2848 1808);
DISPLAY 0.617021 (-2848 1808);
PAINT PINK (-2848 1808);
FORCEPROP 2 LAST CDS_LIB mstr_standard
J 0
(-2850 1800);
PAINT MONO (-2850 1800);
DISPLAY INVISIBLE (-2850 1800);
FORCEPROP 1 LAST BODY_TYPE PLUMBING
J 2
(-2850 1750);
DISPLAY 1.595745 (-2850 1750);
PAINT GREEN (-2850 1750);
DISPLAY INVISIBLE (-2850 1750);
FORCEPROP 1 LAST HDL_TAP TRUE
J 2
(-3175 1675);
DISPLAY 1.595745 (-3175 1675);
PAINT GREEN (-3175 1675);
DISPLAY INVISIBLE (-3175 1675);
FORCEPROP 1 LAST PATH I105
J 2
(-2848 1800);
DISPLAY 0.872340 (-2848 1800);
PAINT GREEN (-2848 1800);
DISPLAY INVISIBLE (-2848 1800);
FORCEADD TAP..6
R 2
(-2850 1750);
FORCEPROP 3 LASTPIN (-2900 1750) SIG_NAME M_E_CKE<2>
J 0
(-2890 1760);
DISPLAY 0.659574 (-2890 1760);
PAINT MONO (-2890 1760);
DISPLAY INVISIBLE (-2890 1760);
FORCEPROP 1 LASTPIN (-2900 1750) BN 2
J 2
(-2848 1758);
DISPLAY 0.617021 (-2848 1758);
PAINT PINK (-2848 1758);
FORCEPROP 2 LAST CDS_LIB mstr_standard
J 0
(-2850 1750);
PAINT MONO (-2850 1750);
DISPLAY INVISIBLE (-2850 1750);
FORCEPROP 1 LAST BODY_TYPE PLUMBING
J 2
(-2850 1700);
DISPLAY 1.595745 (-2850 1700);
PAINT GREEN (-2850 1700);
DISPLAY INVISIBLE (-2850 1700);
FORCEPROP 1 LAST HDL_TAP TRUE
J 2
(-3175 1625);
DISPLAY 1.595745 (-3175 1625);
PAINT GREEN (-3175 1625);
DISPLAY INVISIBLE (-3175 1625);
FORCEPROP 1 LAST PATH I106
J 2
(-2848 1750);
DISPLAY 0.872340 (-2848 1750);
PAINT GREEN (-2848 1750);
DISPLAY INVISIBLE (-2848 1750);
FORCEADD TAP..6
R 2
(-2850 1900);
FORCEPROP 3 LASTPIN (-2900 1900) SIG_NAME M_E_MA<0>
J 0
(-2890 1910);
DISPLAY 0.659574 (-2890 1910);
PAINT MONO (-2890 1910);
DISPLAY INVISIBLE (-2890 1910);
FORCEPROP 1 LASTPIN (-2900 1900) BN 0
J 2
(-2848 1908);
DISPLAY 0.617021 (-2848 1908);
PAINT PINK (-2848 1908);
FORCEPROP 2 LAST CDS_LIB mstr_standard
J 0
(-2850 1900);
PAINT MONO (-2850 1900);
DISPLAY INVISIBLE (-2850 1900);
FORCEPROP 1 LAST BODY_TYPE PLUMBING
J 2
(-2850 1850);
DISPLAY 1.595745 (-2850 1850);
PAINT GREEN (-2850 1850);
DISPLAY INVISIBLE (-2850 1850);
FORCEPROP 1 LAST HDL_TAP TRUE
J 2
(-3175 1775);
DISPLAY 1.595745 (-3175 1775);
PAINT GREEN (-3175 1775);
DISPLAY INVISIBLE (-3175 1775);
FORCEPROP 1 LAST PATH I107
J 2
(-2848 1900);
DISPLAY 0.872340 (-2848 1900);
PAINT GREEN (-2848 1900);
DISPLAY INVISIBLE (-2848 1900);
FORCEADD TAP..6
R 2
(-2850 1950);
FORCEPROP 3 LASTPIN (-2900 1950) SIG_NAME M_E_MA<1>
J 0
(-2890 1960);
DISPLAY 0.659574 (-2890 1960);
PAINT MONO (-2890 1960);
DISPLAY INVISIBLE (-2890 1960);
FORCEPROP 1 LASTPIN (-2900 1950) BN 1
J 2
(-2848 1958);
DISPLAY 0.617021 (-2848 1958);
PAINT PINK (-2848 1958);
FORCEPROP 2 LAST CDS_LIB mstr_standard
J 0
(-2850 1950);
PAINT MONO (-2850 1950);
DISPLAY INVISIBLE (-2850 1950);
FORCEPROP 1 LAST BODY_TYPE PLUMBING
J 2
(-2850 1900);
DISPLAY 1.595745 (-2850 1900);
PAINT GREEN (-2850 1900);
DISPLAY INVISIBLE (-2850 1900);
FORCEPROP 1 LAST HDL_TAP TRUE
J 2
(-3175 1825);
DISPLAY 1.595745 (-3175 1825);
PAINT GREEN (-3175 1825);
DISPLAY INVISIBLE (-3175 1825);
FORCEPROP 1 LAST PATH I108
J 2
(-2848 1950);
DISPLAY 0.872340 (-2848 1950);
PAINT GREEN (-2848 1950);
DISPLAY INVISIBLE (-2848 1950);
FORCEADD TAP..6
R 2
(-2850 2050);
FORCEPROP 3 LASTPIN (-2900 2050) SIG_NAME M_E_MA<3>
J 0
(-2890 2060);
DISPLAY 0.659574 (-2890 2060);
PAINT MONO (-2890 2060);
DISPLAY INVISIBLE (-2890 2060);
FORCEPROP 1 LASTPIN (-2900 2050) BN 3
J 2
(-2848 2058);
DISPLAY 0.617021 (-2848 2058);
PAINT PINK (-2848 2058);
FORCEPROP 2 LAST CDS_LIB mstr_standard
J 0
(-2850 2050);
PAINT MONO (-2850 2050);
DISPLAY INVISIBLE (-2850 2050);
FORCEPROP 1 LAST BODY_TYPE PLUMBING
J 2
(-2850 2000);
DISPLAY 1.595745 (-2850 2000);
PAINT GREEN (-2850 2000);
DISPLAY INVISIBLE (-2850 2000);
FORCEPROP 1 LAST HDL_TAP TRUE
J 2
(-3175 1925);
DISPLAY 1.595745 (-3175 1925);
PAINT GREEN (-3175 1925);
DISPLAY INVISIBLE (-3175 1925);
FORCEPROP 1 LAST PATH I109
J 2
(-2848 2050);
DISPLAY 0.872340 (-2848 2050);
PAINT GREEN (-2848 2050);
DISPLAY INVISIBLE (-2848 2050);
FORCEADD TAP..6
(-5575 900);
FORCEPROP 3 LASTPIN (-5525 900) SIG_NAME M_E_CLK_DP<2>
J 0
(-5515 910);
DISPLAY 0.659574 (-5515 910);
PAINT MONO (-5515 910);
DISPLAY INVISIBLE (-5515 910);
FORCEPROP 1 LASTPIN (-5525 900) BN 2
J 0
(-5577 908);
DISPLAY 0.617021 (-5577 908);
PAINT PINK (-5577 908);
FORCEPROP 2 LAST CDS_LIB mstr_standard
J 0
(-5575 900);
PAINT MONO (-5575 900);
DISPLAY INVISIBLE (-5575 900);
FORCEPROP 1 LAST BODY_TYPE PLUMBING
J 0
(-5575 850);
DISPLAY 1.595745 (-5575 850);
PAINT GREEN (-5575 850);
DISPLAY INVISIBLE (-5575 850);
FORCEPROP 1 LAST HDL_TAP TRUE
J 0
(-5250 775);
DISPLAY 1.595745 (-5250 775);
PAINT GREEN (-5250 775);
DISPLAY INVISIBLE (-5250 775);
FORCEPROP 1 LAST PATH I11
J 0
(-5577 900);
DISPLAY 0.872340 (-5577 900);
PAINT GREEN (-5577 900);
DISPLAY INVISIBLE (-5577 900);
FORCEADD TAP..6
R 2
(-2850 2000);
FORCEPROP 3 LASTPIN (-2900 2000) SIG_NAME M_E_MA<2>
J 0
(-2890 2010);
DISPLAY 0.659574 (-2890 2010);
PAINT MONO (-2890 2010);
DISPLAY INVISIBLE (-2890 2010);
FORCEPROP 1 LASTPIN (-2900 2000) BN 2
J 2
(-2848 2008);
DISPLAY 0.617021 (-2848 2008);
PAINT PINK (-2848 2008);
FORCEPROP 2 LAST CDS_LIB mstr_standard
J 0
(-2850 2000);
PAINT MONO (-2850 2000);
DISPLAY INVISIBLE (-2850 2000);
FORCEPROP 1 LAST BODY_TYPE PLUMBING
J 2
(-2850 1950);
DISPLAY 1.595745 (-2850 1950);
PAINT GREEN (-2850 1950);
DISPLAY INVISIBLE (-2850 1950);
FORCEPROP 1 LAST HDL_TAP TRUE
J 2
(-3175 1875);
DISPLAY 1.595745 (-3175 1875);
PAINT GREEN (-3175 1875);
DISPLAY INVISIBLE (-3175 1875);
FORCEPROP 1 LAST PATH I110
J 2
(-2848 2000);
DISPLAY 0.872340 (-2848 2000);
PAINT GREEN (-2848 2000);
DISPLAY INVISIBLE (-2848 2000);
FORCEADD TAP..6
R 2
(-2850 2100);
FORCEPROP 3 LASTPIN (-2900 2100) SIG_NAME M_E_MA<4>
J 0
(-2890 2110);
DISPLAY 0.659574 (-2890 2110);
PAINT MONO (-2890 2110);
DISPLAY INVISIBLE (-2890 2110);
FORCEPROP 1 LASTPIN (-2900 2100) BN 4
J 2
(-2848 2108);
DISPLAY 0.617021 (-2848 2108);
PAINT PINK (-2848 2108);
FORCEPROP 2 LAST CDS_LIB mstr_standard
J 0
(-2850 2100);
PAINT MONO (-2850 2100);
DISPLAY INVISIBLE (-2850 2100);
FORCEPROP 1 LAST BODY_TYPE PLUMBING
J 2
(-2850 2050);
DISPLAY 1.595745 (-2850 2050);
PAINT GREEN (-2850 2050);
DISPLAY INVISIBLE (-2850 2050);
FORCEPROP 1 LAST HDL_TAP TRUE
J 2
(-3175 1975);
DISPLAY 1.595745 (-3175 1975);
PAINT GREEN (-3175 1975);
DISPLAY INVISIBLE (-3175 1975);
FORCEPROP 1 LAST PATH I111
J 2
(-2848 2100);
DISPLAY 0.872340 (-2848 2100);
PAINT GREEN (-2848 2100);
DISPLAY INVISIBLE (-2848 2100);
FORCEADD TAP..6
R 2
(-2850 2150);
FORCEPROP 3 LASTPIN (-2900 2150) SIG_NAME M_E_MA<5>
J 0
(-2890 2160);
DISPLAY 0.659574 (-2890 2160);
PAINT MONO (-2890 2160);
DISPLAY INVISIBLE (-2890 2160);
FORCEPROP 1 LASTPIN (-2900 2150) BN 5
J 2
(-2848 2158);
DISPLAY 0.617021 (-2848 2158);
PAINT PINK (-2848 2158);
FORCEPROP 2 LAST CDS_LIB mstr_standard
J 0
(-2850 2150);
PAINT MONO (-2850 2150);
DISPLAY INVISIBLE (-2850 2150);
FORCEPROP 1 LAST BODY_TYPE PLUMBING
J 2
(-2850 2100);
DISPLAY 1.595745 (-2850 2100);
PAINT GREEN (-2850 2100);
DISPLAY INVISIBLE (-2850 2100);
FORCEPROP 1 LAST HDL_TAP TRUE
J 2
(-3175 2025);
DISPLAY 1.595745 (-3175 2025);
PAINT GREEN (-3175 2025);
DISPLAY INVISIBLE (-3175 2025);
FORCEPROP 1 LAST PATH I112
J 2
(-2848 2150);
DISPLAY 0.872340 (-2848 2150);
PAINT GREEN (-2848 2150);
DISPLAY INVISIBLE (-2848 2150);
FORCEADD TAP..6
R 2
(-2850 2200);
FORCEPROP 3 LASTPIN (-2900 2200) SIG_NAME M_E_MA<6>
J 0
(-2890 2210);
DISPLAY 0.659574 (-2890 2210);
PAINT MONO (-2890 2210);
DISPLAY INVISIBLE (-2890 2210);
FORCEPROP 1 LASTPIN (-2900 2200) BN 6
J 2
(-2848 2208);
DISPLAY 0.617021 (-2848 2208);
PAINT PINK (-2848 2208);
FORCEPROP 2 LAST CDS_LIB mstr_standard
J 0
(-2850 2200);
PAINT MONO (-2850 2200);
DISPLAY INVISIBLE (-2850 2200);
FORCEPROP 1 LAST BODY_TYPE PLUMBING
J 2
(-2850 2150);
DISPLAY 1.595745 (-2850 2150);
PAINT GREEN (-2850 2150);
DISPLAY INVISIBLE (-2850 2150);
FORCEPROP 1 LAST HDL_TAP TRUE
J 2
(-3175 2075);
DISPLAY 1.595745 (-3175 2075);
PAINT GREEN (-3175 2075);
DISPLAY INVISIBLE (-3175 2075);
FORCEPROP 1 LAST PATH I113
J 2
(-2848 2200);
DISPLAY 0.872340 (-2848 2200);
PAINT GREEN (-2848 2200);
DISPLAY INVISIBLE (-2848 2200);
FORCEADD TAP..6
R 2
(-2850 2350);
FORCEPROP 3 LASTPIN (-2900 2350) SIG_NAME M_E_MA<9>
J 0
(-2890 2360);
DISPLAY 0.659574 (-2890 2360);
PAINT MONO (-2890 2360);
DISPLAY INVISIBLE (-2890 2360);
FORCEPROP 1 LASTPIN (-2900 2350) BN 9
J 2
(-2848 2358);
DISPLAY 0.617021 (-2848 2358);
PAINT PINK (-2848 2358);
FORCEPROP 2 LAST CDS_LIB mstr_standard
J 0
(-2850 2350);
PAINT MONO (-2850 2350);
DISPLAY INVISIBLE (-2850 2350);
FORCEPROP 1 LAST BODY_TYPE PLUMBING
J 2
(-2850 2300);
DISPLAY 1.595745 (-2850 2300);
PAINT GREEN (-2850 2300);
DISPLAY INVISIBLE (-2850 2300);
FORCEPROP 1 LAST HDL_TAP TRUE
J 2
(-3175 2225);
DISPLAY 1.595745 (-3175 2225);
PAINT GREEN (-3175 2225);
DISPLAY INVISIBLE (-3175 2225);
FORCEPROP 1 LAST PATH I114
J 2
(-2848 2350);
DISPLAY 0.872340 (-2848 2350);
PAINT GREEN (-2848 2350);
DISPLAY INVISIBLE (-2848 2350);
FORCEADD TAP..6
R 2
(-2850 2300);
FORCEPROP 3 LASTPIN (-2900 2300) SIG_NAME M_E_MA<8>
J 0
(-2890 2310);
DISPLAY 0.659574 (-2890 2310);
PAINT MONO (-2890 2310);
DISPLAY INVISIBLE (-2890 2310);
FORCEPROP 1 LASTPIN (-2900 2300) BN 8
J 2
(-2848 2308);
DISPLAY 0.617021 (-2848 2308);
PAINT PINK (-2848 2308);
FORCEPROP 2 LAST CDS_LIB mstr_standard
J 0
(-2850 2300);
PAINT MONO (-2850 2300);
DISPLAY INVISIBLE (-2850 2300);
FORCEPROP 1 LAST BODY_TYPE PLUMBING
J 2
(-2850 2250);
DISPLAY 1.595745 (-2850 2250);
PAINT GREEN (-2850 2250);
DISPLAY INVISIBLE (-2850 2250);
FORCEPROP 1 LAST HDL_TAP TRUE
J 2
(-3175 2175);
DISPLAY 1.595745 (-3175 2175);
PAINT GREEN (-3175 2175);
DISPLAY INVISIBLE (-3175 2175);
FORCEPROP 1 LAST PATH I115
J 2
(-2848 2300);
DISPLAY 0.872340 (-2848 2300);
PAINT GREEN (-2848 2300);
DISPLAY INVISIBLE (-2848 2300);
FORCEADD TAP..6
R 2
(-2850 2250);
FORCEPROP 3 LASTPIN (-2900 2250) SIG_NAME M_E_MA<7>
J 0
(-2890 2260);
DISPLAY 0.659574 (-2890 2260);
PAINT MONO (-2890 2260);
DISPLAY INVISIBLE (-2890 2260);
FORCEPROP 1 LASTPIN (-2900 2250) BN 7
J 2
(-2848 2258);
DISPLAY 0.617021 (-2848 2258);
PAINT PINK (-2848 2258);
FORCEPROP 2 LAST CDS_LIB mstr_standard
J 0
(-2850 2250);
PAINT MONO (-2850 2250);
DISPLAY INVISIBLE (-2850 2250);
FORCEPROP 1 LAST BODY_TYPE PLUMBING
J 2
(-2850 2200);
DISPLAY 1.595745 (-2850 2200);
PAINT GREEN (-2850 2200);
DISPLAY INVISIBLE (-2850 2200);
FORCEPROP 1 LAST HDL_TAP TRUE
J 2
(-3175 2125);
DISPLAY 1.595745 (-3175 2125);
PAINT GREEN (-3175 2125);
DISPLAY INVISIBLE (-3175 2125);
FORCEPROP 1 LAST PATH I116
J 2
(-2848 2250);
DISPLAY 0.872340 (-2848 2250);
PAINT GREEN (-2848 2250);
DISPLAY INVISIBLE (-2848 2250);
FORCEADD TAP..6
R 2
(-2850 2450);
FORCEPROP 3 LASTPIN (-2900 2450) SIG_NAME M_E_MA<11>
J 0
(-2890 2460);
DISPLAY 0.659574 (-2890 2460);
PAINT MONO (-2890 2460);
DISPLAY INVISIBLE (-2890 2460);
FORCEPROP 1 LASTPIN (-2900 2450) BN 11
J 2
(-2848 2458);
DISPLAY 0.617021 (-2848 2458);
PAINT PINK (-2848 2458);
FORCEPROP 2 LAST CDS_LIB mstr_standard
J 0
(-2850 2450);
PAINT MONO (-2850 2450);
DISPLAY INVISIBLE (-2850 2450);
FORCEPROP 1 LAST BODY_TYPE PLUMBING
J 2
(-2850 2400);
DISPLAY 1.595745 (-2850 2400);
PAINT GREEN (-2850 2400);
DISPLAY INVISIBLE (-2850 2400);
FORCEPROP 1 LAST HDL_TAP TRUE
J 2
(-3175 2325);
DISPLAY 1.595745 (-3175 2325);
PAINT GREEN (-3175 2325);
DISPLAY INVISIBLE (-3175 2325);
FORCEPROP 1 LAST PATH I117
J 2
(-2848 2450);
DISPLAY 0.872340 (-2848 2450);
PAINT GREEN (-2848 2450);
DISPLAY INVISIBLE (-2848 2450);
FORCEADD TAP..6
R 2
(-2850 2400);
FORCEPROP 3 LASTPIN (-2900 2400) SIG_NAME M_E_MA<10>
J 0
(-2890 2410);
DISPLAY 0.659574 (-2890 2410);
PAINT MONO (-2890 2410);
DISPLAY INVISIBLE (-2890 2410);
FORCEPROP 1 LASTPIN (-2900 2400) BN 10
J 2
(-2848 2408);
DISPLAY 0.617021 (-2848 2408);
PAINT PINK (-2848 2408);
FORCEPROP 2 LAST CDS_LIB mstr_standard
J 0
(-2850 2400);
PAINT MONO (-2850 2400);
DISPLAY INVISIBLE (-2850 2400);
FORCEPROP 1 LAST BODY_TYPE PLUMBING
J 2
(-2850 2350);
DISPLAY 1.595745 (-2850 2350);
PAINT GREEN (-2850 2350);
DISPLAY INVISIBLE (-2850 2350);
FORCEPROP 1 LAST HDL_TAP TRUE
J 2
(-3175 2275);
DISPLAY 1.595745 (-3175 2275);
PAINT GREEN (-3175 2275);
DISPLAY INVISIBLE (-3175 2275);
FORCEPROP 1 LAST PATH I118
J 2
(-2848 2400);
DISPLAY 0.872340 (-2848 2400);
PAINT GREEN (-2848 2400);
DISPLAY INVISIBLE (-2848 2400);
FORCEADD TAP..6
R 2
(-2850 2500);
FORCEPROP 3 LASTPIN (-2900 2500) SIG_NAME M_E_MA<12>
J 0
(-2890 2510);
DISPLAY 0.659574 (-2890 2510);
PAINT MONO (-2890 2510);
DISPLAY INVISIBLE (-2890 2510);
FORCEPROP 1 LASTPIN (-2900 2500) BN 12
J 2
(-2848 2508);
DISPLAY 0.617021 (-2848 2508);
PAINT PINK (-2848 2508);
FORCEPROP 2 LAST CDS_LIB mstr_standard
J 0
(-2850 2500);
PAINT MONO (-2850 2500);
DISPLAY INVISIBLE (-2850 2500);
FORCEPROP 1 LAST BODY_TYPE PLUMBING
J 2
(-2850 2450);
DISPLAY 1.595745 (-2850 2450);
PAINT GREEN (-2850 2450);
DISPLAY INVISIBLE (-2850 2450);
FORCEPROP 1 LAST HDL_TAP TRUE
J 2
(-3175 2375);
DISPLAY 1.595745 (-3175 2375);
PAINT GREEN (-3175 2375);
DISPLAY INVISIBLE (-3175 2375);
FORCEPROP 1 LAST PATH I119
J 2
(-2848 2500);
DISPLAY 0.872340 (-2848 2500);
PAINT GREEN (-2848 2500);
DISPLAY INVISIBLE (-2848 2500);
FORCEADD TAP..6
(-5575 950);
FORCEPROP 3 LASTPIN (-5525 950) SIG_NAME M_E_CLK_DP<3>
J 0
(-5515 960);
DISPLAY 0.659574 (-5515 960);
PAINT MONO (-5515 960);
DISPLAY INVISIBLE (-5515 960);
FORCEPROP 1 LASTPIN (-5525 950) BN 3
J 0
(-5577 958);
DISPLAY 0.617021 (-5577 958);
PAINT PINK (-5577 958);
FORCEPROP 2 LAST CDS_LIB mstr_standard
J 0
(-5575 950);
PAINT MONO (-5575 950);
DISPLAY INVISIBLE (-5575 950);
FORCEPROP 1 LAST BODY_TYPE PLUMBING
J 0
(-5575 900);
DISPLAY 1.595745 (-5575 900);
PAINT GREEN (-5575 900);
DISPLAY INVISIBLE (-5575 900);
FORCEPROP 1 LAST HDL_TAP TRUE
J 0
(-5250 825);
DISPLAY 1.595745 (-5250 825);
PAINT GREEN (-5250 825);
DISPLAY INVISIBLE (-5250 825);
FORCEPROP 1 LAST PATH I12
J 0
(-5577 950);
DISPLAY 0.872340 (-5577 950);
PAINT GREEN (-5577 950);
DISPLAY INVISIBLE (-5577 950);
FORCEADD TAP..6
R 2
(-2850 2550);
FORCEPROP 3 LASTPIN (-2900 2550) SIG_NAME M_E_MA<13>
J 0
(-2890 2560);
DISPLAY 0.659574 (-2890 2560);
PAINT MONO (-2890 2560);
DISPLAY INVISIBLE (-2890 2560);
FORCEPROP 1 LASTPIN (-2900 2550) BN 13
J 2
(-2848 2558);
DISPLAY 0.617021 (-2848 2558);
PAINT PINK (-2848 2558);
FORCEPROP 2 LAST CDS_LIB mstr_standard
J 0
(-2850 2550);
PAINT MONO (-2850 2550);
DISPLAY INVISIBLE (-2850 2550);
FORCEPROP 1 LAST BODY_TYPE PLUMBING
J 2
(-2850 2500);
DISPLAY 1.595745 (-2850 2500);
PAINT GREEN (-2850 2500);
DISPLAY INVISIBLE (-2850 2500);
FORCEPROP 1 LAST HDL_TAP TRUE
J 2
(-3175 2425);
DISPLAY 1.595745 (-3175 2425);
PAINT GREEN (-3175 2425);
DISPLAY INVISIBLE (-3175 2425);
FORCEPROP 1 LAST PATH I120
J 2
(-2848 2550);
DISPLAY 0.872340 (-2848 2550);
PAINT GREEN (-2848 2550);
DISPLAY INVISIBLE (-2848 2550);
FORCEADD TAP..6
R 2
(-2850 2600);
FORCEPROP 3 LASTPIN (-2900 2600) SIG_NAME M_E_MA<14>
J 0
(-2890 2610);
DISPLAY 0.659574 (-2890 2610);
PAINT MONO (-2890 2610);
DISPLAY INVISIBLE (-2890 2610);
FORCEPROP 1 LASTPIN (-2900 2600) BN 14
J 2
(-2848 2608);
DISPLAY 0.617021 (-2848 2608);
PAINT PINK (-2848 2608);
FORCEPROP 2 LAST CDS_LIB mstr_standard
J 0
(-2850 2600);
PAINT MONO (-2850 2600);
DISPLAY INVISIBLE (-2850 2600);
FORCEPROP 1 LAST BODY_TYPE PLUMBING
J 2
(-2850 2550);
DISPLAY 1.595745 (-2850 2550);
PAINT GREEN (-2850 2550);
DISPLAY INVISIBLE (-2850 2550);
FORCEPROP 1 LAST HDL_TAP TRUE
J 2
(-3175 2475);
DISPLAY 1.595745 (-3175 2475);
PAINT GREEN (-3175 2475);
DISPLAY INVISIBLE (-3175 2475);
FORCEPROP 1 LAST PATH I121
J 2
(-2848 2600);
DISPLAY 0.872340 (-2848 2600);
PAINT GREEN (-2848 2600);
DISPLAY INVISIBLE (-2848 2600);
FORCEADD TAP..6
R 2
(-2850 2700);
FORCEPROP 3 LASTPIN (-2900 2700) SIG_NAME M_E_MA<16>
J 0
(-2890 2710);
DISPLAY 0.659574 (-2890 2710);
PAINT MONO (-2890 2710);
DISPLAY INVISIBLE (-2890 2710);
FORCEPROP 1 LASTPIN (-2900 2700) BN 16
J 2
(-2848 2708);
DISPLAY 0.617021 (-2848 2708);
PAINT PINK (-2848 2708);
FORCEPROP 2 LAST CDS_LIB mstr_standard
J 0
(-2850 2700);
PAINT MONO (-2850 2700);
DISPLAY INVISIBLE (-2850 2700);
FORCEPROP 1 LAST BODY_TYPE PLUMBING
J 2
(-2850 2650);
DISPLAY 1.595745 (-2850 2650);
PAINT GREEN (-2850 2650);
DISPLAY INVISIBLE (-2850 2650);
FORCEPROP 1 LAST HDL_TAP TRUE
J 2
(-3175 2575);
DISPLAY 1.595745 (-3175 2575);
PAINT GREEN (-3175 2575);
DISPLAY INVISIBLE (-3175 2575);
FORCEPROP 1 LAST PATH I122
J 2
(-2848 2700);
DISPLAY 0.872340 (-2848 2700);
PAINT GREEN (-2848 2700);
DISPLAY INVISIBLE (-2848 2700);
FORCEADD TAP..6
R 2
(-2850 2650);
FORCEPROP 3 LASTPIN (-2900 2650) SIG_NAME M_E_MA<15>
J 0
(-2890 2660);
DISPLAY 0.659574 (-2890 2660);
PAINT MONO (-2890 2660);
DISPLAY INVISIBLE (-2890 2660);
FORCEPROP 1 LASTPIN (-2900 2650) BN 15
J 2
(-2848 2658);
DISPLAY 0.617021 (-2848 2658);
PAINT PINK (-2848 2658);
FORCEPROP 2 LAST CDS_LIB mstr_standard
J 0
(-2850 2650);
PAINT MONO (-2850 2650);
DISPLAY INVISIBLE (-2850 2650);
FORCEPROP 1 LAST BODY_TYPE PLUMBING
J 2
(-2850 2600);
DISPLAY 1.595745 (-2850 2600);
PAINT GREEN (-2850 2600);
DISPLAY INVISIBLE (-2850 2600);
FORCEPROP 1 LAST HDL_TAP TRUE
J 2
(-3175 2525);
DISPLAY 1.595745 (-3175 2525);
PAINT GREEN (-3175 2525);
DISPLAY INVISIBLE (-3175 2525);
FORCEPROP 1 LAST PATH I123
J 2
(-2848 2650);
DISPLAY 0.872340 (-2848 2650);
PAINT GREEN (-2848 2650);
DISPLAY INVISIBLE (-2848 2650);
FORCEADD TAP..6
R 2
(-2850 2750);
FORCEPROP 3 LASTPIN (-2900 2750) SIG_NAME M_E_MA<17>
J 0
(-2890 2760);
DISPLAY 0.659574 (-2890 2760);
PAINT MONO (-2890 2760);
DISPLAY INVISIBLE (-2890 2760);
FORCEPROP 1 LASTPIN (-2900 2750) BN 17
J 2
(-2848 2758);
DISPLAY 0.617021 (-2848 2758);
PAINT PINK (-2848 2758);
FORCEPROP 2 LAST CDS_LIB mstr_standard
J 0
(-2850 2750);
PAINT MONO (-2850 2750);
DISPLAY INVISIBLE (-2850 2750);
FORCEPROP 1 LAST BODY_TYPE PLUMBING
J 2
(-2850 2700);
DISPLAY 1.595745 (-2850 2700);
PAINT GREEN (-2850 2700);
DISPLAY INVISIBLE (-2850 2700);
FORCEPROP 1 LAST HDL_TAP TRUE
J 2
(-3175 2625);
DISPLAY 1.595745 (-3175 2625);
PAINT GREEN (-3175 2625);
DISPLAY INVISIBLE (-3175 2625);
FORCEPROP 1 LAST PATH I124
J 2
(-2848 2750);
DISPLAY 0.872340 (-2848 2750);
PAINT GREEN (-2848 2750);
DISPLAY INVISIBLE (-2848 2750);
FORCEADD TAP..6
R 2
(-2850 2850);
FORCEPROP 3 LASTPIN (-2900 2850) SIG_NAME M_E_DQS_DN<0>
J 0
(-2890 2860);
DISPLAY 0.659574 (-2890 2860);
PAINT MONO (-2890 2860);
DISPLAY INVISIBLE (-2890 2860);
FORCEPROP 1 LASTPIN (-2900 2850) BN 0
J 2
(-2848 2858);
DISPLAY 0.617021 (-2848 2858);
PAINT PINK (-2848 2858);
FORCEPROP 2 LAST CDS_LIB mstr_standard
J 0
(-2850 2850);
PAINT MONO (-2850 2850);
DISPLAY INVISIBLE (-2850 2850);
FORCEPROP 1 LAST BODY_TYPE PLUMBING
J 2
(-2850 2800);
DISPLAY 1.595745 (-2850 2800);
PAINT GREEN (-2850 2800);
DISPLAY INVISIBLE (-2850 2800);
FORCEPROP 1 LAST HDL_TAP TRUE
J 2
(-3175 2725);
DISPLAY 1.595745 (-3175 2725);
PAINT GREEN (-3175 2725);
DISPLAY INVISIBLE (-3175 2725);
FORCEPROP 1 LAST PATH I125
J 2
(-2848 2850);
DISPLAY 0.872340 (-2848 2850);
PAINT GREEN (-2848 2850);
DISPLAY INVISIBLE (-2848 2850);
FORCEADD TAP..6
R 2
(-2850 2950);
FORCEPROP 3 LASTPIN (-2900 2950) SIG_NAME M_E_DQS_DN<2>
J 0
(-2890 2960);
DISPLAY 0.659574 (-2890 2960);
PAINT MONO (-2890 2960);
DISPLAY INVISIBLE (-2890 2960);
FORCEPROP 1 LASTPIN (-2900 2950) BN 2
J 2
(-2848 2958);
DISPLAY 0.617021 (-2848 2958);
PAINT PINK (-2848 2958);
FORCEPROP 2 LAST CDS_LIB mstr_standard
J 0
(-2850 2950);
PAINT MONO (-2850 2950);
DISPLAY INVISIBLE (-2850 2950);
FORCEPROP 1 LAST BODY_TYPE PLUMBING
J 2
(-2850 2900);
DISPLAY 1.595745 (-2850 2900);
PAINT GREEN (-2850 2900);
DISPLAY INVISIBLE (-2850 2900);
FORCEPROP 1 LAST HDL_TAP TRUE
J 2
(-3175 2825);
DISPLAY 1.595745 (-3175 2825);
PAINT GREEN (-3175 2825);
DISPLAY INVISIBLE (-3175 2825);
FORCEPROP 1 LAST PATH I126
J 2
(-2848 2950);
DISPLAY 0.872340 (-2848 2950);
PAINT GREEN (-2848 2950);
DISPLAY INVISIBLE (-2848 2950);
FORCEADD TAP..6
R 2
(-2850 2900);
FORCEPROP 3 LASTPIN (-2900 2900) SIG_NAME M_E_DQS_DN<1>
J 0
(-2890 2910);
DISPLAY 0.659574 (-2890 2910);
PAINT MONO (-2890 2910);
DISPLAY INVISIBLE (-2890 2910);
FORCEPROP 1 LASTPIN (-2900 2900) BN 1
J 2
(-2848 2908);
DISPLAY 0.617021 (-2848 2908);
PAINT PINK (-2848 2908);
FORCEPROP 2 LAST CDS_LIB mstr_standard
J 0
(-2850 2900);
PAINT MONO (-2850 2900);
DISPLAY INVISIBLE (-2850 2900);
FORCEPROP 1 LAST BODY_TYPE PLUMBING
J 2
(-2850 2850);
DISPLAY 1.595745 (-2850 2850);
PAINT GREEN (-2850 2850);
DISPLAY INVISIBLE (-2850 2850);
FORCEPROP 1 LAST HDL_TAP TRUE
J 2
(-3175 2775);
DISPLAY 1.595745 (-3175 2775);
PAINT GREEN (-3175 2775);
DISPLAY INVISIBLE (-3175 2775);
FORCEPROP 1 LAST PATH I127
J 2
(-2848 2900);
DISPLAY 0.872340 (-2848 2900);
PAINT GREEN (-2848 2900);
DISPLAY INVISIBLE (-2848 2900);
FORCEADD TAP..6
R 2
(-2850 3000);
FORCEPROP 3 LASTPIN (-2900 3000) SIG_NAME M_E_DQS_DN<3>
J 0
(-2890 3010);
DISPLAY 0.659574 (-2890 3010);
PAINT MONO (-2890 3010);
DISPLAY INVISIBLE (-2890 3010);
FORCEPROP 1 LASTPIN (-2900 3000) BN 3
J 2
(-2848 3008);
DISPLAY 0.617021 (-2848 3008);
PAINT PINK (-2848 3008);
FORCEPROP 2 LAST CDS_LIB mstr_standard
J 0
(-2850 3000);
PAINT MONO (-2850 3000);
DISPLAY INVISIBLE (-2850 3000);
FORCEPROP 1 LAST BODY_TYPE PLUMBING
J 2
(-2850 2950);
DISPLAY 1.595745 (-2850 2950);
PAINT GREEN (-2850 2950);
DISPLAY INVISIBLE (-2850 2950);
FORCEPROP 1 LAST HDL_TAP TRUE
J 2
(-3175 2875);
DISPLAY 1.595745 (-3175 2875);
PAINT GREEN (-3175 2875);
DISPLAY INVISIBLE (-3175 2875);
FORCEPROP 1 LAST PATH I128
J 2
(-2848 3000);
DISPLAY 0.872340 (-2848 3000);
PAINT GREEN (-2848 3000);
DISPLAY INVISIBLE (-2848 3000);
FORCEADD TAP..6
R 2
(-2850 3050);
FORCEPROP 3 LASTPIN (-2900 3050) SIG_NAME M_E_DQS_DN<4>
J 0
(-2890 3060);
DISPLAY 0.659574 (-2890 3060);
PAINT MONO (-2890 3060);
DISPLAY INVISIBLE (-2890 3060);
FORCEPROP 1 LASTPIN (-2900 3050) BN 4
J 2
(-2848 3058);
DISPLAY 0.617021 (-2848 3058);
PAINT PINK (-2848 3058);
FORCEPROP 2 LAST CDS_LIB mstr_standard
J 0
(-2850 3050);
PAINT MONO (-2850 3050);
DISPLAY INVISIBLE (-2850 3050);
FORCEPROP 1 LAST BODY_TYPE PLUMBING
J 2
(-2850 3000);
DISPLAY 1.595745 (-2850 3000);
PAINT GREEN (-2850 3000);
DISPLAY INVISIBLE (-2850 3000);
FORCEPROP 1 LAST HDL_TAP TRUE
J 2
(-3175 2925);
DISPLAY 1.595745 (-3175 2925);
PAINT GREEN (-3175 2925);
DISPLAY INVISIBLE (-3175 2925);
FORCEPROP 1 LAST PATH I129
J 2
(-2848 3050);
DISPLAY 0.872340 (-2848 3050);
PAINT GREEN (-2848 3050);
DISPLAY INVISIBLE (-2848 3050);
FORCEADD TAP..6
(-5575 1050);
FORCEPROP 3 LASTPIN (-5525 1050) SIG_NAME M_E_ECC<0>
J 0
(-5515 1060);
DISPLAY 0.659574 (-5515 1060);
PAINT MONO (-5515 1060);
DISPLAY INVISIBLE (-5515 1060);
FORCEPROP 1 LASTPIN (-5525 1050) BN 0
J 0
(-5577 1058);
DISPLAY 0.617021 (-5577 1058);
PAINT PINK (-5577 1058);
FORCEPROP 2 LAST CDS_LIB mstr_standard
J 0
(-5575 1050);
PAINT MONO (-5575 1050);
DISPLAY INVISIBLE (-5575 1050);
FORCEPROP 1 LAST BODY_TYPE PLUMBING
J 0
(-5575 1000);
DISPLAY 1.595745 (-5575 1000);
PAINT GREEN (-5575 1000);
DISPLAY INVISIBLE (-5575 1000);
FORCEPROP 1 LAST HDL_TAP TRUE
J 0
(-5250 925);
DISPLAY 1.595745 (-5250 925);
PAINT GREEN (-5250 925);
DISPLAY INVISIBLE (-5250 925);
FORCEPROP 1 LAST PATH I13
J 0
(-5577 1050);
DISPLAY 0.872340 (-5577 1050);
PAINT GREEN (-5577 1050);
DISPLAY INVISIBLE (-5577 1050);
FORCEADD TAP..6
R 2
(-2850 3100);
FORCEPROP 3 LASTPIN (-2900 3100) SIG_NAME M_E_DQS_DN<5>
J 0
(-2890 3110);
DISPLAY 0.659574 (-2890 3110);
PAINT MONO (-2890 3110);
DISPLAY INVISIBLE (-2890 3110);
FORCEPROP 1 LASTPIN (-2900 3100) BN 5
J 2
(-2848 3108);
DISPLAY 0.617021 (-2848 3108);
PAINT PINK (-2848 3108);
FORCEPROP 2 LAST CDS_LIB mstr_standard
J 0
(-2850 3100);
PAINT MONO (-2850 3100);
DISPLAY INVISIBLE (-2850 3100);
FORCEPROP 1 LAST BODY_TYPE PLUMBING
J 2
(-2850 3050);
DISPLAY 1.595745 (-2850 3050);
PAINT GREEN (-2850 3050);
DISPLAY INVISIBLE (-2850 3050);
FORCEPROP 1 LAST HDL_TAP TRUE
J 2
(-3175 2975);
DISPLAY 1.595745 (-3175 2975);
PAINT GREEN (-3175 2975);
DISPLAY INVISIBLE (-3175 2975);
FORCEPROP 1 LAST PATH I130
J 2
(-2848 3100);
DISPLAY 0.872340 (-2848 3100);
PAINT GREEN (-2848 3100);
DISPLAY INVISIBLE (-2848 3100);
FORCEADD TAP..6
R 2
(-2850 3200);
FORCEPROP 3 LASTPIN (-2900 3200) SIG_NAME M_E_DQS_DN<7>
J 0
(-2890 3210);
DISPLAY 0.659574 (-2890 3210);
PAINT MONO (-2890 3210);
DISPLAY INVISIBLE (-2890 3210);
FORCEPROP 1 LASTPIN (-2900 3200) BN 7
J 2
(-2848 3208);
DISPLAY 0.617021 (-2848 3208);
PAINT PINK (-2848 3208);
FORCEPROP 2 LAST CDS_LIB mstr_standard
J 0
(-2850 3200);
PAINT MONO (-2850 3200);
DISPLAY INVISIBLE (-2850 3200);
FORCEPROP 1 LAST BODY_TYPE PLUMBING
J 2
(-2850 3150);
DISPLAY 1.595745 (-2850 3150);
PAINT GREEN (-2850 3150);
DISPLAY INVISIBLE (-2850 3150);
FORCEPROP 1 LAST HDL_TAP TRUE
J 2
(-3175 3075);
DISPLAY 1.595745 (-3175 3075);
PAINT GREEN (-3175 3075);
DISPLAY INVISIBLE (-3175 3075);
FORCEPROP 1 LAST PATH I131
J 2
(-2848 3200);
DISPLAY 0.872340 (-2848 3200);
PAINT GREEN (-2848 3200);
DISPLAY INVISIBLE (-2848 3200);
FORCEADD TAP..6
R 2
(-2850 3150);
FORCEPROP 3 LASTPIN (-2900 3150) SIG_NAME M_E_DQS_DN<6>
J 0
(-2890 3160);
DISPLAY 0.659574 (-2890 3160);
PAINT MONO (-2890 3160);
DISPLAY INVISIBLE (-2890 3160);
FORCEPROP 1 LASTPIN (-2900 3150) BN 6
J 2
(-2848 3158);
DISPLAY 0.617021 (-2848 3158);
PAINT PINK (-2848 3158);
FORCEPROP 2 LAST CDS_LIB mstr_standard
J 0
(-2850 3150);
PAINT MONO (-2850 3150);
DISPLAY INVISIBLE (-2850 3150);
FORCEPROP 1 LAST BODY_TYPE PLUMBING
J 2
(-2850 3100);
DISPLAY 1.595745 (-2850 3100);
PAINT GREEN (-2850 3100);
DISPLAY INVISIBLE (-2850 3100);
FORCEPROP 1 LAST HDL_TAP TRUE
J 2
(-3175 3025);
DISPLAY 1.595745 (-3175 3025);
PAINT GREEN (-3175 3025);
DISPLAY INVISIBLE (-3175 3025);
FORCEPROP 1 LAST PATH I132
J 2
(-2848 3150);
DISPLAY 0.872340 (-2848 3150);
PAINT GREEN (-2848 3150);
DISPLAY INVISIBLE (-2848 3150);
FORCEADD TAP..6
R 2
(-2850 3250);
FORCEPROP 3 LASTPIN (-2900 3250) SIG_NAME M_E_DQS_DN<8>
J 0
(-2890 3260);
DISPLAY 0.659574 (-2890 3260);
PAINT MONO (-2890 3260);
DISPLAY INVISIBLE (-2890 3260);
FORCEPROP 1 LASTPIN (-2900 3250) BN 8
J 2
(-2848 3258);
DISPLAY 0.617021 (-2848 3258);
PAINT PINK (-2848 3258);
FORCEPROP 2 LAST CDS_LIB mstr_standard
J 0
(-2850 3250);
PAINT MONO (-2850 3250);
DISPLAY INVISIBLE (-2850 3250);
FORCEPROP 1 LAST BODY_TYPE PLUMBING
J 2
(-2850 3200);
DISPLAY 1.595745 (-2850 3200);
PAINT GREEN (-2850 3200);
DISPLAY INVISIBLE (-2850 3200);
FORCEPROP 1 LAST HDL_TAP TRUE
J 2
(-3175 3125);
DISPLAY 1.595745 (-3175 3125);
PAINT GREEN (-3175 3125);
DISPLAY INVISIBLE (-3175 3125);
FORCEPROP 1 LAST PATH I133
J 2
(-2848 3250);
DISPLAY 0.872340 (-2848 3250);
PAINT GREEN (-2848 3250);
DISPLAY INVISIBLE (-2848 3250);
FORCEADD TAP..6
R 2
(-2850 3350);
FORCEPROP 3 LASTPIN (-2900 3350) SIG_NAME M_E_DQS_DN<10>
J 0
(-2890 3360);
DISPLAY 0.659574 (-2890 3360);
PAINT MONO (-2890 3360);
DISPLAY INVISIBLE (-2890 3360);
FORCEPROP 1 LASTPIN (-2900 3350) BN 10
J 2
(-2848 3358);
DISPLAY 0.617021 (-2848 3358);
PAINT PINK (-2848 3358);
FORCEPROP 2 LAST CDS_LIB mstr_standard
J 0
(-2850 3350);
PAINT MONO (-2850 3350);
DISPLAY INVISIBLE (-2850 3350);
FORCEPROP 1 LAST BODY_TYPE PLUMBING
J 2
(-2850 3300);
DISPLAY 1.595745 (-2850 3300);
PAINT GREEN (-2850 3300);
DISPLAY INVISIBLE (-2850 3300);
FORCEPROP 1 LAST HDL_TAP TRUE
J 2
(-3175 3225);
DISPLAY 1.595745 (-3175 3225);
PAINT GREEN (-3175 3225);
DISPLAY INVISIBLE (-3175 3225);
FORCEPROP 1 LAST PATH I134
J 2
(-2848 3350);
DISPLAY 0.872340 (-2848 3350);
PAINT GREEN (-2848 3350);
DISPLAY INVISIBLE (-2848 3350);
FORCEADD TAP..6
R 2
(-2850 3300);
FORCEPROP 3 LASTPIN (-2900 3300) SIG_NAME M_E_DQS_DN<9>
J 0
(-2890 3310);
DISPLAY 0.659574 (-2890 3310);
PAINT MONO (-2890 3310);
DISPLAY INVISIBLE (-2890 3310);
FORCEPROP 1 LASTPIN (-2900 3300) BN 9
J 2
(-2848 3308);
DISPLAY 0.617021 (-2848 3308);
PAINT PINK (-2848 3308);
FORCEPROP 2 LAST CDS_LIB mstr_standard
J 0
(-2850 3300);
PAINT MONO (-2850 3300);
DISPLAY INVISIBLE (-2850 3300);
FORCEPROP 1 LAST BODY_TYPE PLUMBING
J 2
(-2850 3250);
DISPLAY 1.595745 (-2850 3250);
PAINT GREEN (-2850 3250);
DISPLAY INVISIBLE (-2850 3250);
FORCEPROP 1 LAST HDL_TAP TRUE
J 2
(-3175 3175);
DISPLAY 1.595745 (-3175 3175);
PAINT GREEN (-3175 3175);
DISPLAY INVISIBLE (-3175 3175);
FORCEPROP 1 LAST PATH I135
J 2
(-2848 3300);
DISPLAY 0.872340 (-2848 3300);
PAINT GREEN (-2848 3300);
DISPLAY INVISIBLE (-2848 3300);
FORCEADD TAP..6
R 2
(-2850 3500);
FORCEPROP 3 LASTPIN (-2900 3500) SIG_NAME M_E_DQS_DN<13>
J 0
(-2890 3510);
DISPLAY 0.659574 (-2890 3510);
PAINT MONO (-2890 3510);
DISPLAY INVISIBLE (-2890 3510);
FORCEPROP 1 LASTPIN (-2900 3500) BN 13
J 2
(-2848 3508);
DISPLAY 0.617021 (-2848 3508);
PAINT PINK (-2848 3508);
FORCEPROP 2 LAST CDS_LIB mstr_standard
J 0
(-2850 3500);
PAINT MONO (-2850 3500);
DISPLAY INVISIBLE (-2850 3500);
FORCEPROP 1 LAST BODY_TYPE PLUMBING
J 2
(-2850 3450);
DISPLAY 1.595745 (-2850 3450);
PAINT GREEN (-2850 3450);
DISPLAY INVISIBLE (-2850 3450);
FORCEPROP 1 LAST HDL_TAP TRUE
J 2
(-3175 3375);
DISPLAY 1.595745 (-3175 3375);
PAINT GREEN (-3175 3375);
DISPLAY INVISIBLE (-3175 3375);
FORCEPROP 1 LAST PATH I136
J 2
(-2848 3500);
DISPLAY 0.872340 (-2848 3500);
PAINT GREEN (-2848 3500);
DISPLAY INVISIBLE (-2848 3500);
FORCEADD TAP..6
R 2
(-2850 3400);
FORCEPROP 3 LASTPIN (-2900 3400) SIG_NAME M_E_DQS_DN<11>
J 0
(-2890 3410);
DISPLAY 0.659574 (-2890 3410);
PAINT MONO (-2890 3410);
DISPLAY INVISIBLE (-2890 3410);
FORCEPROP 1 LASTPIN (-2900 3400) BN 11
J 2
(-2848 3408);
DISPLAY 0.617021 (-2848 3408);
PAINT PINK (-2848 3408);
FORCEPROP 2 LAST CDS_LIB mstr_standard
J 0
(-2850 3400);
PAINT MONO (-2850 3400);
DISPLAY INVISIBLE (-2850 3400);
FORCEPROP 1 LAST BODY_TYPE PLUMBING
J 2
(-2850 3350);
DISPLAY 1.595745 (-2850 3350);
PAINT GREEN (-2850 3350);
DISPLAY INVISIBLE (-2850 3350);
FORCEPROP 1 LAST HDL_TAP TRUE
J 2
(-3175 3275);
DISPLAY 1.595745 (-3175 3275);
PAINT GREEN (-3175 3275);
DISPLAY INVISIBLE (-3175 3275);
FORCEPROP 1 LAST PATH I137
J 2
(-2848 3400);
DISPLAY 0.872340 (-2848 3400);
PAINT GREEN (-2848 3400);
DISPLAY INVISIBLE (-2848 3400);
FORCEADD TAP..6
R 2
(-2850 3450);
FORCEPROP 3 LASTPIN (-2900 3450) SIG_NAME M_E_DQS_DN<12>
J 0
(-2890 3460);
DISPLAY 0.659574 (-2890 3460);
PAINT MONO (-2890 3460);
DISPLAY INVISIBLE (-2890 3460);
FORCEPROP 1 LASTPIN (-2900 3450) BN 12
J 2
(-2848 3458);
DISPLAY 0.617021 (-2848 3458);
PAINT PINK (-2848 3458);
FORCEPROP 2 LAST CDS_LIB mstr_standard
J 0
(-2850 3450);
PAINT MONO (-2850 3450);
DISPLAY INVISIBLE (-2850 3450);
FORCEPROP 1 LAST BODY_TYPE PLUMBING
J 2
(-2850 3400);
DISPLAY 1.595745 (-2850 3400);
PAINT GREEN (-2850 3400);
DISPLAY INVISIBLE (-2850 3400);
FORCEPROP 1 LAST HDL_TAP TRUE
J 2
(-3175 3325);
DISPLAY 1.595745 (-3175 3325);
PAINT GREEN (-3175 3325);
DISPLAY INVISIBLE (-3175 3325);
FORCEPROP 1 LAST PATH I138
J 2
(-2848 3450);
DISPLAY 0.872340 (-2848 3450);
PAINT GREEN (-2848 3450);
DISPLAY INVISIBLE (-2848 3450);
FORCEADD TAP..6
R 2
(-2850 3600);
FORCEPROP 3 LASTPIN (-2900 3600) SIG_NAME M_E_DQS_DN<15>
J 0
(-2890 3610);
DISPLAY 0.659574 (-2890 3610);
PAINT MONO (-2890 3610);
DISPLAY INVISIBLE (-2890 3610);
FORCEPROP 1 LASTPIN (-2900 3600) BN 15
J 2
(-2848 3608);
DISPLAY 0.617021 (-2848 3608);
PAINT PINK (-2848 3608);
FORCEPROP 2 LAST CDS_LIB mstr_standard
J 0
(-2850 3600);
PAINT MONO (-2850 3600);
DISPLAY INVISIBLE (-2850 3600);
FORCEPROP 1 LAST BODY_TYPE PLUMBING
J 2
(-2850 3550);
DISPLAY 1.595745 (-2850 3550);
PAINT GREEN (-2850 3550);
DISPLAY INVISIBLE (-2850 3550);
FORCEPROP 1 LAST HDL_TAP TRUE
J 2
(-3175 3475);
DISPLAY 1.595745 (-3175 3475);
PAINT GREEN (-3175 3475);
DISPLAY INVISIBLE (-3175 3475);
FORCEPROP 1 LAST PATH I139
J 2
(-2848 3600);
DISPLAY 0.872340 (-2848 3600);
PAINT GREEN (-2848 3600);
DISPLAY INVISIBLE (-2848 3600);
FORCEADD TAP..6
(-5575 1100);
FORCEPROP 3 LASTPIN (-5525 1100) SIG_NAME M_E_ECC<1>
J 0
(-5515 1110);
DISPLAY 0.659574 (-5515 1110);
PAINT MONO (-5515 1110);
DISPLAY INVISIBLE (-5515 1110);
FORCEPROP 1 LASTPIN (-5525 1100) BN 1
J 0
(-5577 1108);
DISPLAY 0.617021 (-5577 1108);
PAINT PINK (-5577 1108);
FORCEPROP 2 LAST CDS_LIB mstr_standard
J 0
(-5575 1100);
PAINT MONO (-5575 1100);
DISPLAY INVISIBLE (-5575 1100);
FORCEPROP 1 LAST BODY_TYPE PLUMBING
J 0
(-5575 1050);
DISPLAY 1.595745 (-5575 1050);
PAINT GREEN (-5575 1050);
DISPLAY INVISIBLE (-5575 1050);
FORCEPROP 1 LAST HDL_TAP TRUE
J 0
(-5250 975);
DISPLAY 1.595745 (-5250 975);
PAINT GREEN (-5250 975);
DISPLAY INVISIBLE (-5250 975);
FORCEPROP 1 LAST PATH I14
J 0
(-5577 1100);
DISPLAY 0.872340 (-5577 1100);
PAINT GREEN (-5577 1100);
DISPLAY INVISIBLE (-5577 1100);
FORCEADD TAP..6
R 2
(-2850 3550);
FORCEPROP 3 LASTPIN (-2900 3550) SIG_NAME M_E_DQS_DN<14>
J 0
(-2890 3560);
DISPLAY 0.659574 (-2890 3560);
PAINT MONO (-2890 3560);
DISPLAY INVISIBLE (-2890 3560);
FORCEPROP 1 LASTPIN (-2900 3550) BN 14
J 2
(-2848 3558);
DISPLAY 0.617021 (-2848 3558);
PAINT PINK (-2848 3558);
FORCEPROP 2 LAST CDS_LIB mstr_standard
J 0
(-2850 3550);
PAINT MONO (-2850 3550);
DISPLAY INVISIBLE (-2850 3550);
FORCEPROP 1 LAST BODY_TYPE PLUMBING
J 2
(-2850 3500);
DISPLAY 1.595745 (-2850 3500);
PAINT GREEN (-2850 3500);
DISPLAY INVISIBLE (-2850 3500);
FORCEPROP 1 LAST HDL_TAP TRUE
J 2
(-3175 3425);
DISPLAY 1.595745 (-3175 3425);
PAINT GREEN (-3175 3425);
DISPLAY INVISIBLE (-3175 3425);
FORCEPROP 1 LAST PATH I140
J 2
(-2848 3550);
DISPLAY 0.872340 (-2848 3550);
PAINT GREEN (-2848 3550);
DISPLAY INVISIBLE (-2848 3550);
FORCEADD TAP..6
R 2
(-2850 3700);
FORCEPROP 3 LASTPIN (-2900 3700) SIG_NAME M_E_DQS_DN<17>
J 0
(-2890 3710);
DISPLAY 0.659574 (-2890 3710);
PAINT MONO (-2890 3710);
DISPLAY INVISIBLE (-2890 3710);
FORCEPROP 1 LASTPIN (-2900 3700) BN 17
J 2
(-2848 3708);
DISPLAY 0.617021 (-2848 3708);
PAINT PINK (-2848 3708);
FORCEPROP 2 LAST CDS_LIB mstr_standard
J 0
(-2850 3700);
PAINT MONO (-2850 3700);
DISPLAY INVISIBLE (-2850 3700);
FORCEPROP 1 LAST BODY_TYPE PLUMBING
J 2
(-2850 3650);
DISPLAY 1.595745 (-2850 3650);
PAINT GREEN (-2850 3650);
DISPLAY INVISIBLE (-2850 3650);
FORCEPROP 1 LAST HDL_TAP TRUE
J 2
(-3175 3575);
DISPLAY 1.595745 (-3175 3575);
PAINT GREEN (-3175 3575);
DISPLAY INVISIBLE (-3175 3575);
FORCEPROP 1 LAST PATH I141
J 2
(-2848 3700);
DISPLAY 0.872340 (-2848 3700);
PAINT GREEN (-2848 3700);
DISPLAY INVISIBLE (-2848 3700);
FORCEADD TAP..6
R 2
(-2850 3650);
FORCEPROP 3 LASTPIN (-2900 3650) SIG_NAME M_E_DQS_DN<16>
J 0
(-2890 3660);
DISPLAY 0.659574 (-2890 3660);
PAINT MONO (-2890 3660);
DISPLAY INVISIBLE (-2890 3660);
FORCEPROP 1 LASTPIN (-2900 3650) BN 16
J 2
(-2848 3658);
DISPLAY 0.617021 (-2848 3658);
PAINT PINK (-2848 3658);
FORCEPROP 2 LAST CDS_LIB mstr_standard
J 0
(-2850 3650);
PAINT MONO (-2850 3650);
DISPLAY INVISIBLE (-2850 3650);
FORCEPROP 1 LAST BODY_TYPE PLUMBING
J 2
(-2850 3600);
DISPLAY 1.595745 (-2850 3600);
PAINT GREEN (-2850 3600);
DISPLAY INVISIBLE (-2850 3600);
FORCEPROP 1 LAST HDL_TAP TRUE
J 2
(-3175 3525);
DISPLAY 1.595745 (-3175 3525);
PAINT GREEN (-3175 3525);
DISPLAY INVISIBLE (-3175 3525);
FORCEPROP 1 LAST PATH I142
J 2
(-2848 3650);
DISPLAY 0.872340 (-2848 3650);
PAINT GREEN (-2848 3650);
DISPLAY INVISIBLE (-2848 3650);
FORCEADD TAP..6
R 2
(-2850 3850);
FORCEPROP 3 LASTPIN (-2900 3850) SIG_NAME M_E_DQS_DP<1>
J 0
(-2890 3860);
DISPLAY 0.659574 (-2890 3860);
PAINT MONO (-2890 3860);
DISPLAY INVISIBLE (-2890 3860);
FORCEPROP 1 LASTPIN (-2900 3850) BN 1
J 2
(-2848 3858);
DISPLAY 0.617021 (-2848 3858);
PAINT PINK (-2848 3858);
FORCEPROP 2 LAST CDS_LIB mstr_standard
J 0
(-2850 3850);
PAINT MONO (-2850 3850);
DISPLAY INVISIBLE (-2850 3850);
FORCEPROP 1 LAST BODY_TYPE PLUMBING
J 2
(-2850 3800);
DISPLAY 1.595745 (-2850 3800);
PAINT GREEN (-2850 3800);
DISPLAY INVISIBLE (-2850 3800);
FORCEPROP 1 LAST HDL_TAP TRUE
J 2
(-3175 3725);
DISPLAY 1.595745 (-3175 3725);
PAINT GREEN (-3175 3725);
DISPLAY INVISIBLE (-3175 3725);
FORCEPROP 1 LAST PATH I143
J 2
(-2848 3850);
DISPLAY 0.872340 (-2848 3850);
PAINT GREEN (-2848 3850);
DISPLAY INVISIBLE (-2848 3850);
FORCEADD TAP..6
R 2
(-2850 3800);
FORCEPROP 3 LASTPIN (-2900 3800) SIG_NAME M_E_DQS_DP<0>
J 0
(-2890 3810);
DISPLAY 0.659574 (-2890 3810);
PAINT MONO (-2890 3810);
DISPLAY INVISIBLE (-2890 3810);
FORCEPROP 1 LASTPIN (-2900 3800) BN 0
J 2
(-2848 3808);
DISPLAY 0.617021 (-2848 3808);
PAINT PINK (-2848 3808);
FORCEPROP 2 LAST CDS_LIB mstr_standard
J 0
(-2850 3800);
PAINT MONO (-2850 3800);
DISPLAY INVISIBLE (-2850 3800);
FORCEPROP 1 LAST BODY_TYPE PLUMBING
J 2
(-2850 3750);
DISPLAY 1.595745 (-2850 3750);
PAINT GREEN (-2850 3750);
DISPLAY INVISIBLE (-2850 3750);
FORCEPROP 1 LAST HDL_TAP TRUE
J 2
(-3175 3675);
DISPLAY 1.595745 (-3175 3675);
PAINT GREEN (-3175 3675);
DISPLAY INVISIBLE (-3175 3675);
FORCEPROP 1 LAST PATH I144
J 2
(-2848 3800);
DISPLAY 0.872340 (-2848 3800);
PAINT GREEN (-2848 3800);
DISPLAY INVISIBLE (-2848 3800);
FORCEADD TAP..6
R 2
(-2850 4000);
FORCEPROP 3 LASTPIN (-2900 4000) SIG_NAME M_E_DQS_DP<4>
J 0
(-2890 4010);
DISPLAY 0.659574 (-2890 4010);
PAINT MONO (-2890 4010);
DISPLAY INVISIBLE (-2890 4010);
FORCEPROP 1 LASTPIN (-2900 4000) BN 4
J 2
(-2848 4008);
DISPLAY 0.617021 (-2848 4008);
PAINT PINK (-2848 4008);
FORCEPROP 2 LAST CDS_LIB mstr_standard
J 0
(-2850 4000);
PAINT MONO (-2850 4000);
DISPLAY INVISIBLE (-2850 4000);
FORCEPROP 1 LAST BODY_TYPE PLUMBING
J 2
(-2850 3950);
DISPLAY 1.595745 (-2850 3950);
PAINT GREEN (-2850 3950);
DISPLAY INVISIBLE (-2850 3950);
FORCEPROP 1 LAST HDL_TAP TRUE
J 2
(-3175 3875);
DISPLAY 1.595745 (-3175 3875);
PAINT GREEN (-3175 3875);
DISPLAY INVISIBLE (-3175 3875);
FORCEPROP 1 LAST PATH I145
J 2
(-2848 4000);
DISPLAY 0.872340 (-2848 4000);
PAINT GREEN (-2848 4000);
DISPLAY INVISIBLE (-2848 4000);
FORCEADD TAP..6
R 2
(-2850 3950);
FORCEPROP 3 LASTPIN (-2900 3950) SIG_NAME M_E_DQS_DP<3>
J 0
(-2890 3960);
DISPLAY 0.659574 (-2890 3960);
PAINT MONO (-2890 3960);
DISPLAY INVISIBLE (-2890 3960);
FORCEPROP 1 LASTPIN (-2900 3950) BN 3
J 2
(-2848 3958);
DISPLAY 0.617021 (-2848 3958);
PAINT PINK (-2848 3958);
FORCEPROP 2 LAST CDS_LIB mstr_standard
J 0
(-2850 3950);
PAINT MONO (-2850 3950);
DISPLAY INVISIBLE (-2850 3950);
FORCEPROP 1 LAST BODY_TYPE PLUMBING
J 2
(-2850 3900);
DISPLAY 1.595745 (-2850 3900);
PAINT GREEN (-2850 3900);
DISPLAY INVISIBLE (-2850 3900);
FORCEPROP 1 LAST HDL_TAP TRUE
J 2
(-3175 3825);
DISPLAY 1.595745 (-3175 3825);
PAINT GREEN (-3175 3825);
DISPLAY INVISIBLE (-3175 3825);
FORCEPROP 1 LAST PATH I146
J 2
(-2848 3950);
DISPLAY 0.872340 (-2848 3950);
PAINT GREEN (-2848 3950);
DISPLAY INVISIBLE (-2848 3950);
FORCEADD TAP..6
R 2
(-2850 3900);
FORCEPROP 3 LASTPIN (-2900 3900) SIG_NAME M_E_DQS_DP<2>
J 0
(-2890 3910);
DISPLAY 0.659574 (-2890 3910);
PAINT MONO (-2890 3910);
DISPLAY INVISIBLE (-2890 3910);
FORCEPROP 1 LASTPIN (-2900 3900) BN 2
J 2
(-2848 3908);
DISPLAY 0.617021 (-2848 3908);
PAINT PINK (-2848 3908);
FORCEPROP 2 LAST CDS_LIB mstr_standard
J 0
(-2850 3900);
PAINT MONO (-2850 3900);
DISPLAY INVISIBLE (-2850 3900);
FORCEPROP 1 LAST BODY_TYPE PLUMBING
J 2
(-2850 3850);
DISPLAY 1.595745 (-2850 3850);
PAINT GREEN (-2850 3850);
DISPLAY INVISIBLE (-2850 3850);
FORCEPROP 1 LAST HDL_TAP TRUE
J 2
(-3175 3775);
DISPLAY 1.595745 (-3175 3775);
PAINT GREEN (-3175 3775);
DISPLAY INVISIBLE (-3175 3775);
FORCEPROP 1 LAST PATH I147
J 2
(-2848 3900);
DISPLAY 0.872340 (-2848 3900);
PAINT GREEN (-2848 3900);
DISPLAY INVISIBLE (-2848 3900);
FORCEADD OFFPAGE..4
(-2000 550);
FORCEPROP 2 LAST $XR1 52 
J 0
(-1724 550);
DISPLAY 0.638298 (-1724 550);
PAINT MONO (-1724 550);
FORCEPROP 2 LAST $XR0 51 
J 0
(-1814 550);
DISPLAY 0.638298 (-1814 550);
PAINT MONO (-1814 550);
FORCEPROP 2 LAST CDS_LIB mstr_standard
J 0
(-2000 550);
PAINT MONO (-2000 550);
DISPLAY INVISIBLE (-2000 550);
FORCEPROP 1 LAST OFFPAGE TRUE
J 0
(-1675 425);
DISPLAY 1.170213 (-1675 425);
PAINT GREEN (-1675 425);
DISPLAY INVISIBLE (-1675 425);
FORCEPROP 1 LAST COMMENT_BODY TRUE
J 0
(-2025 450);
DISPLAY 1.170213 (-2025 450);
PAINT GREEN (-2025 450);
DISPLAY INVISIBLE (-2025 450);
FORCEPROP 2 LAST PATH I148
J 0
(-1825 625);
DISPLAY 1.021277 (-1825 625);
PAINT ORANGE (-1825 625);
DISPLAY INVISIBLE (-1825 625);
FORCEADD OFFPAGE..2
(-2000 500);
FORCEPROP 2 LAST $XR1 52 
J 0
(-1721 500);
DISPLAY 0.638298 (-1721 500);
PAINT MONO (-1721 500);
FORCEPROP 2 LAST $XR0 51 
J 0
(-1811 500);
DISPLAY 0.638298 (-1811 500);
PAINT MONO (-1811 500);
FORCEPROP 2 LAST CDS_LIB mstr_standard
J 0
(-2000 500);
PAINT MONO (-2000 500);
DISPLAY INVISIBLE (-2000 500);
FORCEPROP 1 LAST OFFPAGE TRUE
J 0
(-1675 375);
DISPLAY 1.170213 (-1675 375);
PAINT GREEN (-1675 375);
DISPLAY INVISIBLE (-1675 375);
FORCEPROP 1 LAST COMMENT_BODY TRUE
J 0
(-2045 405);
DISPLAY 1.170213 (-2045 405);
PAINT GREEN (-2045 405);
DISPLAY INVISIBLE (-2045 405);
FORCEPROP 2 LAST PATH I149
J 0
(-1825 575);
DISPLAY 1.021277 (-1825 575);
PAINT ORANGE (-1825 575);
DISPLAY INVISIBLE (-1825 575);
FORCEADD TAP..6
(-5575 1150);
FORCEPROP 3 LASTPIN (-5525 1150) SIG_NAME M_E_ECC<2>
J 0
(-5515 1160);
DISPLAY 0.659574 (-5515 1160);
PAINT MONO (-5515 1160);
DISPLAY INVISIBLE (-5515 1160);
FORCEPROP 1 LASTPIN (-5525 1150) BN 2
J 0
(-5577 1158);
DISPLAY 0.617021 (-5577 1158);
PAINT PINK (-5577 1158);
FORCEPROP 2 LAST CDS_LIB mstr_standard
J 0
(-5575 1150);
PAINT MONO (-5575 1150);
DISPLAY INVISIBLE (-5575 1150);
FORCEPROP 1 LAST BODY_TYPE PLUMBING
J 0
(-5575 1100);
DISPLAY 1.595745 (-5575 1100);
PAINT GREEN (-5575 1100);
DISPLAY INVISIBLE (-5575 1100);
FORCEPROP 1 LAST HDL_TAP TRUE
J 0
(-5250 1025);
DISPLAY 1.595745 (-5250 1025);
PAINT GREEN (-5250 1025);
DISPLAY INVISIBLE (-5250 1025);
FORCEPROP 1 LAST PATH I15
J 0
(-5577 1150);
DISPLAY 0.872340 (-5577 1150);
PAINT GREEN (-5577 1150);
DISPLAY INVISIBLE (-5577 1150);
FORCEADD OFFPAGE..2
(-2000 600);
FORCEPROP 2 LAST $XR1 52 
J 0
(-1721 600);
DISPLAY 0.638298 (-1721 600);
PAINT MONO (-1721 600);
FORCEPROP 2 LAST $XR0 51 
J 0
(-1811 600);
DISPLAY 0.638298 (-1811 600);
PAINT MONO (-1811 600);
FORCEPROP 2 LAST CDS_LIB mstr_standard
J 0
(-2000 600);
PAINT MONO (-2000 600);
DISPLAY INVISIBLE (-2000 600);
FORCEPROP 1 LAST OFFPAGE TRUE
J 0
(-1675 475);
DISPLAY 1.170213 (-1675 475);
PAINT GREEN (-1675 475);
DISPLAY INVISIBLE (-1675 475);
FORCEPROP 1 LAST COMMENT_BODY TRUE
J 0
(-2045 505);
DISPLAY 1.170213 (-2045 505);
PAINT GREEN (-2045 505);
DISPLAY INVISIBLE (-2045 505);
FORCEPROP 2 LAST PATH I150
J 0
(-1825 675);
DISPLAY 1.021277 (-1825 675);
PAINT ORANGE (-1825 675);
DISPLAY INVISIBLE (-1825 675);
FORCEADD OFFPAGE..2
(-2000 800);
FORCEPROP 2 LAST $XR1 52 
J 0
(-1721 800);
DISPLAY 0.638298 (-1721 800);
PAINT MONO (-1721 800);
FORCEPROP 2 LAST $XR0 51 
J 0
(-1811 800);
DISPLAY 0.638298 (-1811 800);
PAINT MONO (-1811 800);
FORCEPROP 2 LAST CDS_LIB mstr_standard
J 0
(-2000 800);
PAINT MONO (-2000 800);
DISPLAY INVISIBLE (-2000 800);
FORCEPROP 1 LAST OFFPAGE TRUE
J 0
(-1675 675);
DISPLAY 1.170213 (-1675 675);
PAINT GREEN (-1675 675);
DISPLAY INVISIBLE (-1675 675);
FORCEPROP 1 LAST COMMENT_BODY TRUE
J 0
(-2045 705);
DISPLAY 1.170213 (-2045 705);
PAINT GREEN (-2045 705);
DISPLAY INVISIBLE (-2045 705);
FORCEPROP 2 LAST PATH I151
J 0
(-1825 875);
DISPLAY 1.021277 (-1825 875);
PAINT ORANGE (-1825 875);
DISPLAY INVISIBLE (-1825 875);
FORCEADD OFFPAGE..2
(-2000 900);
FORCEPROP 2 LAST $XR1 52 
J 0
(-1721 900);
DISPLAY 0.638298 (-1721 900);
PAINT MONO (-1721 900);
FORCEPROP 2 LAST $XR0 51 
J 0
(-1811 900);
DISPLAY 0.638298 (-1811 900);
PAINT MONO (-1811 900);
FORCEPROP 2 LAST CDS_LIB mstr_standard
J 0
(-2000 900);
PAINT MONO (-2000 900);
DISPLAY INVISIBLE (-2000 900);
FORCEPROP 1 LAST OFFPAGE TRUE
J 0
(-1675 775);
DISPLAY 1.170213 (-1675 775);
PAINT GREEN (-1675 775);
DISPLAY INVISIBLE (-1675 775);
FORCEPROP 1 LAST COMMENT_BODY TRUE
J 0
(-2045 805);
DISPLAY 1.170213 (-2045 805);
PAINT GREEN (-2045 805);
DISPLAY INVISIBLE (-2045 805);
FORCEPROP 2 LAST PATH I152
J 0
(-1825 975);
DISPLAY 1.021277 (-1825 975);
PAINT ORANGE (-1825 975);
DISPLAY INVISIBLE (-1825 975);
FORCEADD OFFPAGE..2
(-2000 1350);
FORCEPROP 2 LAST $XR1 52 
J 0
(-1721 1350);
DISPLAY 0.638298 (-1721 1350);
PAINT MONO (-1721 1350);
FORCEPROP 2 LAST $XR0 51 
J 0
(-1811 1350);
DISPLAY 0.638298 (-1811 1350);
PAINT MONO (-1811 1350);
FORCEPROP 2 LAST CDS_LIB mstr_standard
J 0
(-2000 1350);
PAINT MONO (-2000 1350);
DISPLAY INVISIBLE (-2000 1350);
FORCEPROP 1 LAST OFFPAGE TRUE
J 0
(-1675 1225);
DISPLAY 1.170213 (-1675 1225);
PAINT GREEN (-1675 1225);
DISPLAY INVISIBLE (-1675 1225);
FORCEPROP 1 LAST COMMENT_BODY TRUE
J 0
(-2045 1255);
DISPLAY 1.170213 (-2045 1255);
PAINT GREEN (-2045 1255);
DISPLAY INVISIBLE (-2045 1255);
FORCEPROP 2 LAST PATH I153
J 0
(-1825 1425);
DISPLAY 1.021277 (-1825 1425);
PAINT ORANGE (-1825 1425);
DISPLAY INVISIBLE (-1825 1425);
FORCEADD OFFPAGE..2
(-2000 1600);
FORCEPROP 2 LAST $XR1 52 
J 0
(-1721 1600);
DISPLAY 0.638298 (-1721 1600);
PAINT MONO (-1721 1600);
FORCEPROP 2 LAST $XR0 51 
J 0
(-1811 1600);
DISPLAY 0.638298 (-1811 1600);
PAINT MONO (-1811 1600);
FORCEPROP 2 LAST CDS_LIB mstr_standard
J 0
(-2000 1600);
PAINT MONO (-2000 1600);
DISPLAY INVISIBLE (-2000 1600);
FORCEPROP 1 LAST OFFPAGE TRUE
J 0
(-1675 1475);
DISPLAY 1.170213 (-1675 1475);
PAINT GREEN (-1675 1475);
DISPLAY INVISIBLE (-1675 1475);
FORCEPROP 1 LAST COMMENT_BODY TRUE
J 0
(-2045 1505);
DISPLAY 1.170213 (-2045 1505);
PAINT GREEN (-2045 1505);
DISPLAY INVISIBLE (-2045 1505);
FORCEPROP 2 LAST PATH I154
J 0
(-1825 1675);
DISPLAY 1.021277 (-1825 1675);
PAINT ORANGE (-1825 1675);
DISPLAY INVISIBLE (-1825 1675);
FORCEADD OFFPAGE..2
(-2000 1850);
FORCEPROP 2 LAST $XR1 52 
J 0
(-1721 1850);
DISPLAY 0.638298 (-1721 1850);
PAINT MONO (-1721 1850);
FORCEPROP 2 LAST $XR0 51 
J 0
(-1811 1850);
DISPLAY 0.638298 (-1811 1850);
PAINT MONO (-1811 1850);
FORCEPROP 2 LAST CDS_LIB mstr_standard
J 0
(-2000 1850);
PAINT MONO (-2000 1850);
DISPLAY INVISIBLE (-2000 1850);
FORCEPROP 1 LAST OFFPAGE TRUE
J 0
(-1675 1725);
DISPLAY 1.170213 (-1675 1725);
PAINT GREEN (-1675 1725);
DISPLAY INVISIBLE (-1675 1725);
FORCEPROP 1 LAST COMMENT_BODY TRUE
J 0
(-2045 1755);
DISPLAY 1.170213 (-2045 1755);
PAINT GREEN (-2045 1755);
DISPLAY INVISIBLE (-2045 1755);
FORCEPROP 2 LAST PATH I155
J 0
(-1825 1925);
DISPLAY 1.021277 (-1825 1925);
PAINT ORANGE (-1825 1925);
DISPLAY INVISIBLE (-1825 1925);
FORCEADD OFFPAGE..2
(-2000 2800);
FORCEPROP 2 LAST $XR1 52 
J 0
(-1721 2800);
DISPLAY 0.638298 (-1721 2800);
PAINT MONO (-1721 2800);
FORCEPROP 2 LAST $XR0 51 
J 0
(-1811 2800);
DISPLAY 0.638298 (-1811 2800);
PAINT MONO (-1811 2800);
FORCEPROP 2 LAST CDS_LIB mstr_standard
J 0
(-2000 2800);
PAINT MONO (-2000 2800);
DISPLAY INVISIBLE (-2000 2800);
FORCEPROP 1 LAST OFFPAGE TRUE
J 0
(-1675 2675);
DISPLAY 1.170213 (-1675 2675);
PAINT GREEN (-1675 2675);
DISPLAY INVISIBLE (-1675 2675);
FORCEPROP 1 LAST COMMENT_BODY TRUE
J 0
(-2045 2705);
DISPLAY 1.170213 (-2045 2705);
PAINT GREEN (-2045 2705);
DISPLAY INVISIBLE (-2045 2705);
FORCEPROP 2 LAST PATH I156
J 0
(-1825 2875);
DISPLAY 1.021277 (-1825 2875);
PAINT ORANGE (-1825 2875);
DISPLAY INVISIBLE (-1825 2875);
FORCEADD OFFPAGE..3
(-2000 3750);
FORCEPROP 2 LAST $XR1 52 
J 0
(-1696 3750);
DISPLAY 0.638298 (-1696 3750);
PAINT MONO (-1696 3750);
FORCEPROP 2 LAST $XR0 51 
J 0
(-1786 3750);
DISPLAY 0.638298 (-1786 3750);
PAINT MONO (-1786 3750);
FORCEPROP 2 LAST CDS_LIB mstr_standard
J 0
(-2000 3750);
PAINT MONO (-2000 3750);
DISPLAY INVISIBLE (-2000 3750);
FORCEPROP 1 LAST OFFPAGE TRUE
J 0
(-1675 3625);
DISPLAY 1.170213 (-1675 3625);
PAINT GREEN (-1675 3625);
DISPLAY INVISIBLE (-1675 3625);
FORCEPROP 1 LAST COMMENT_BODY TRUE
J 0
(-2050 3650);
DISPLAY 1.170213 (-2050 3650);
PAINT GREEN (-2050 3650);
DISPLAY INVISIBLE (-2050 3650);
FORCEPROP 2 LAST PATH I157
J 0
(-1800 3825);
DISPLAY 1.021277 (-1800 3825);
PAINT ORANGE (-1800 3825);
DISPLAY INVISIBLE (-1800 3825);
FORCEADD TAP..6
R 2
(-2850 4100);
FORCEPROP 3 LASTPIN (-2900 4100) SIG_NAME M_E_DQS_DP<6>
J 0
(-2890 4110);
DISPLAY 0.659574 (-2890 4110);
PAINT MONO (-2890 4110);
DISPLAY INVISIBLE (-2890 4110);
FORCEPROP 1 LASTPIN (-2900 4100) BN 6
J 2
(-2848 4108);
DISPLAY 0.617021 (-2848 4108);
PAINT PINK (-2848 4108);
FORCEPROP 2 LAST CDS_LIB mstr_standard
J 0
(-2850 4100);
PAINT MONO (-2850 4100);
DISPLAY INVISIBLE (-2850 4100);
FORCEPROP 1 LAST BODY_TYPE PLUMBING
J 2
(-2850 4050);
DISPLAY 1.595745 (-2850 4050);
PAINT GREEN (-2850 4050);
DISPLAY INVISIBLE (-2850 4050);
FORCEPROP 1 LAST HDL_TAP TRUE
J 2
(-3175 3975);
DISPLAY 1.595745 (-3175 3975);
PAINT GREEN (-3175 3975);
DISPLAY INVISIBLE (-3175 3975);
FORCEPROP 1 LAST PATH I158
J 2
(-2848 4100);
DISPLAY 0.872340 (-2848 4100);
PAINT GREEN (-2848 4100);
DISPLAY INVISIBLE (-2848 4100);
FORCEADD TAP..6
R 2
(-2850 4050);
FORCEPROP 3 LASTPIN (-2900 4050) SIG_NAME M_E_DQS_DP<5>
J 0
(-2890 4060);
DISPLAY 0.659574 (-2890 4060);
PAINT MONO (-2890 4060);
DISPLAY INVISIBLE (-2890 4060);
FORCEPROP 1 LASTPIN (-2900 4050) BN 5
J 2
(-2848 4058);
DISPLAY 0.617021 (-2848 4058);
PAINT PINK (-2848 4058);
FORCEPROP 2 LAST CDS_LIB mstr_standard
J 0
(-2850 4050);
PAINT MONO (-2850 4050);
DISPLAY INVISIBLE (-2850 4050);
FORCEPROP 1 LAST BODY_TYPE PLUMBING
J 2
(-2850 4000);
DISPLAY 1.595745 (-2850 4000);
PAINT GREEN (-2850 4000);
DISPLAY INVISIBLE (-2850 4000);
FORCEPROP 1 LAST HDL_TAP TRUE
J 2
(-3175 3925);
DISPLAY 1.595745 (-3175 3925);
PAINT GREEN (-3175 3925);
DISPLAY INVISIBLE (-3175 3925);
FORCEPROP 1 LAST PATH I159
J 2
(-2848 4050);
DISPLAY 0.872340 (-2848 4050);
PAINT GREEN (-2848 4050);
DISPLAY INVISIBLE (-2848 4050);
FORCEADD TAP..6
(-5575 1200);
FORCEPROP 3 LASTPIN (-5525 1200) SIG_NAME M_E_ECC<3>
J 0
(-5515 1210);
DISPLAY 0.659574 (-5515 1210);
PAINT MONO (-5515 1210);
DISPLAY INVISIBLE (-5515 1210);
FORCEPROP 1 LASTPIN (-5525 1200) BN 3
J 0
(-5577 1208);
DISPLAY 0.617021 (-5577 1208);
PAINT PINK (-5577 1208);
FORCEPROP 2 LAST CDS_LIB mstr_standard
J 0
(-5575 1200);
PAINT MONO (-5575 1200);
DISPLAY INVISIBLE (-5575 1200);
FORCEPROP 1 LAST BODY_TYPE PLUMBING
J 0
(-5575 1150);
DISPLAY 1.595745 (-5575 1150);
PAINT GREEN (-5575 1150);
DISPLAY INVISIBLE (-5575 1150);
FORCEPROP 1 LAST HDL_TAP TRUE
J 0
(-5250 1075);
DISPLAY 1.595745 (-5250 1075);
PAINT GREEN (-5250 1075);
DISPLAY INVISIBLE (-5250 1075);
FORCEPROP 1 LAST PATH I16
J 0
(-5577 1200);
DISPLAY 0.872340 (-5577 1200);
PAINT GREEN (-5577 1200);
DISPLAY INVISIBLE (-5577 1200);
FORCEADD TAP..6
R 2
(-2850 4150);
FORCEPROP 3 LASTPIN (-2900 4150) SIG_NAME M_E_DQS_DP<7>
J 0
(-2890 4160);
DISPLAY 0.659574 (-2890 4160);
PAINT MONO (-2890 4160);
DISPLAY INVISIBLE (-2890 4160);
FORCEPROP 1 LASTPIN (-2900 4150) BN 7
J 2
(-2848 4158);
DISPLAY 0.617021 (-2848 4158);
PAINT PINK (-2848 4158);
FORCEPROP 2 LAST CDS_LIB mstr_standard
J 0
(-2850 4150);
PAINT MONO (-2850 4150);
DISPLAY INVISIBLE (-2850 4150);
FORCEPROP 1 LAST BODY_TYPE PLUMBING
J 2
(-2850 4100);
DISPLAY 1.595745 (-2850 4100);
PAINT GREEN (-2850 4100);
DISPLAY INVISIBLE (-2850 4100);
FORCEPROP 1 LAST HDL_TAP TRUE
J 2
(-3175 4025);
DISPLAY 1.595745 (-3175 4025);
PAINT GREEN (-3175 4025);
DISPLAY INVISIBLE (-3175 4025);
FORCEPROP 1 LAST PATH I160
J 2
(-2848 4150);
DISPLAY 0.872340 (-2848 4150);
PAINT GREEN (-2848 4150);
DISPLAY INVISIBLE (-2848 4150);
FORCEADD TAP..6
R 2
(-2850 4250);
FORCEPROP 3 LASTPIN (-2900 4250) SIG_NAME M_E_DQS_DP<9>
J 0
(-2890 4260);
DISPLAY 0.659574 (-2890 4260);
PAINT MONO (-2890 4260);
DISPLAY INVISIBLE (-2890 4260);
FORCEPROP 1 LASTPIN (-2900 4250) BN 9
J 2
(-2848 4258);
DISPLAY 0.617021 (-2848 4258);
PAINT PINK (-2848 4258);
FORCEPROP 2 LAST CDS_LIB mstr_standard
J 0
(-2850 4250);
PAINT MONO (-2850 4250);
DISPLAY INVISIBLE (-2850 4250);
FORCEPROP 1 LAST BODY_TYPE PLUMBING
J 2
(-2850 4200);
DISPLAY 1.595745 (-2850 4200);
PAINT GREEN (-2850 4200);
DISPLAY INVISIBLE (-2850 4200);
FORCEPROP 1 LAST HDL_TAP TRUE
J 2
(-3175 4125);
DISPLAY 1.595745 (-3175 4125);
PAINT GREEN (-3175 4125);
DISPLAY INVISIBLE (-3175 4125);
FORCEPROP 1 LAST PATH I161
J 2
(-2848 4250);
DISPLAY 0.872340 (-2848 4250);
PAINT GREEN (-2848 4250);
DISPLAY INVISIBLE (-2848 4250);
FORCEADD TAP..6
R 2
(-2850 4200);
FORCEPROP 3 LASTPIN (-2900 4200) SIG_NAME M_E_DQS_DP<8>
J 0
(-2890 4210);
DISPLAY 0.659574 (-2890 4210);
PAINT MONO (-2890 4210);
DISPLAY INVISIBLE (-2890 4210);
FORCEPROP 1 LASTPIN (-2900 4200) BN 8
J 2
(-2848 4208);
DISPLAY 0.617021 (-2848 4208);
PAINT PINK (-2848 4208);
FORCEPROP 2 LAST CDS_LIB mstr_standard
J 0
(-2850 4200);
PAINT MONO (-2850 4200);
DISPLAY INVISIBLE (-2850 4200);
FORCEPROP 1 LAST BODY_TYPE PLUMBING
J 2
(-2850 4150);
DISPLAY 1.595745 (-2850 4150);
PAINT GREEN (-2850 4150);
DISPLAY INVISIBLE (-2850 4150);
FORCEPROP 1 LAST HDL_TAP TRUE
J 2
(-3175 4075);
DISPLAY 1.595745 (-3175 4075);
PAINT GREEN (-3175 4075);
DISPLAY INVISIBLE (-3175 4075);
FORCEPROP 1 LAST PATH I162
J 2
(-2848 4200);
DISPLAY 0.872340 (-2848 4200);
PAINT GREEN (-2848 4200);
DISPLAY INVISIBLE (-2848 4200);
FORCEADD TAP..6
R 2
(-2850 4400);
FORCEPROP 3 LASTPIN (-2900 4400) SIG_NAME M_E_DQS_DP<12>
J 0
(-2890 4410);
DISPLAY 0.659574 (-2890 4410);
PAINT MONO (-2890 4410);
DISPLAY INVISIBLE (-2890 4410);
FORCEPROP 1 LASTPIN (-2900 4400) BN 12
J 2
(-2848 4408);
DISPLAY 0.617021 (-2848 4408);
PAINT PINK (-2848 4408);
FORCEPROP 2 LAST CDS_LIB mstr_standard
J 0
(-2850 4400);
PAINT MONO (-2850 4400);
DISPLAY INVISIBLE (-2850 4400);
FORCEPROP 1 LAST BODY_TYPE PLUMBING
J 2
(-2850 4350);
DISPLAY 1.595745 (-2850 4350);
PAINT GREEN (-2850 4350);
DISPLAY INVISIBLE (-2850 4350);
FORCEPROP 1 LAST HDL_TAP TRUE
J 2
(-3175 4275);
DISPLAY 1.595745 (-3175 4275);
PAINT GREEN (-3175 4275);
DISPLAY INVISIBLE (-3175 4275);
FORCEPROP 1 LAST PATH I163
J 2
(-2848 4400);
DISPLAY 0.872340 (-2848 4400);
PAINT GREEN (-2848 4400);
DISPLAY INVISIBLE (-2848 4400);
FORCEADD TAP..6
R 2
(-2850 4350);
FORCEPROP 3 LASTPIN (-2900 4350) SIG_NAME M_E_DQS_DP<11>
J 0
(-2890 4360);
DISPLAY 0.659574 (-2890 4360);
PAINT MONO (-2890 4360);
DISPLAY INVISIBLE (-2890 4360);
FORCEPROP 1 LASTPIN (-2900 4350) BN 11
J 2
(-2848 4358);
DISPLAY 0.617021 (-2848 4358);
PAINT PINK (-2848 4358);
FORCEPROP 2 LAST CDS_LIB mstr_standard
J 0
(-2850 4350);
PAINT MONO (-2850 4350);
DISPLAY INVISIBLE (-2850 4350);
FORCEPROP 1 LAST BODY_TYPE PLUMBING
J 2
(-2850 4300);
DISPLAY 1.595745 (-2850 4300);
PAINT GREEN (-2850 4300);
DISPLAY INVISIBLE (-2850 4300);
FORCEPROP 1 LAST HDL_TAP TRUE
J 2
(-3175 4225);
DISPLAY 1.595745 (-3175 4225);
PAINT GREEN (-3175 4225);
DISPLAY INVISIBLE (-3175 4225);
FORCEPROP 1 LAST PATH I164
J 2
(-2848 4350);
DISPLAY 0.872340 (-2848 4350);
PAINT GREEN (-2848 4350);
DISPLAY INVISIBLE (-2848 4350);
FORCEADD TAP..6
R 2
(-2850 4300);
FORCEPROP 3 LASTPIN (-2900 4300) SIG_NAME M_E_DQS_DP<10>
J 0
(-2890 4310);
DISPLAY 0.659574 (-2890 4310);
PAINT MONO (-2890 4310);
DISPLAY INVISIBLE (-2890 4310);
FORCEPROP 1 LASTPIN (-2900 4300) BN 10
J 2
(-2848 4308);
DISPLAY 0.617021 (-2848 4308);
PAINT PINK (-2848 4308);
FORCEPROP 2 LAST CDS_LIB mstr_standard
J 0
(-2850 4300);
PAINT MONO (-2850 4300);
DISPLAY INVISIBLE (-2850 4300);
FORCEPROP 1 LAST BODY_TYPE PLUMBING
J 2
(-2850 4250);
DISPLAY 1.595745 (-2850 4250);
PAINT GREEN (-2850 4250);
DISPLAY INVISIBLE (-2850 4250);
FORCEPROP 1 LAST HDL_TAP TRUE
J 2
(-3175 4175);
DISPLAY 1.595745 (-3175 4175);
PAINT GREEN (-3175 4175);
DISPLAY INVISIBLE (-3175 4175);
FORCEPROP 1 LAST PATH I165
J 2
(-2848 4300);
DISPLAY 0.872340 (-2848 4300);
PAINT GREEN (-2848 4300);
DISPLAY INVISIBLE (-2848 4300);
FORCEADD TAP..6
R 2
(-2850 4450);
FORCEPROP 3 LASTPIN (-2900 4450) SIG_NAME M_E_DQS_DP<13>
J 0
(-2890 4460);
DISPLAY 0.659574 (-2890 4460);
PAINT MONO (-2890 4460);
DISPLAY INVISIBLE (-2890 4460);
FORCEPROP 1 LASTPIN (-2900 4450) BN 13
J 2
(-2848 4458);
DISPLAY 0.617021 (-2848 4458);
PAINT PINK (-2848 4458);
FORCEPROP 2 LAST CDS_LIB mstr_standard
J 0
(-2850 4450);
PAINT MONO (-2850 4450);
DISPLAY INVISIBLE (-2850 4450);
FORCEPROP 1 LAST BODY_TYPE PLUMBING
J 2
(-2850 4400);
DISPLAY 1.595745 (-2850 4400);
PAINT GREEN (-2850 4400);
DISPLAY INVISIBLE (-2850 4400);
FORCEPROP 1 LAST HDL_TAP TRUE
J 2
(-3175 4325);
DISPLAY 1.595745 (-3175 4325);
PAINT GREEN (-3175 4325);
DISPLAY INVISIBLE (-3175 4325);
FORCEPROP 1 LAST PATH I166
J 2
(-2848 4450);
DISPLAY 0.872340 (-2848 4450);
PAINT GREEN (-2848 4450);
DISPLAY INVISIBLE (-2848 4450);
FORCEADD TAP..6
R 2
(-2850 4500);
FORCEPROP 3 LASTPIN (-2900 4500) SIG_NAME M_E_DQS_DP<14>
J 0
(-2890 4510);
DISPLAY 0.659574 (-2890 4510);
PAINT MONO (-2890 4510);
DISPLAY INVISIBLE (-2890 4510);
FORCEPROP 1 LASTPIN (-2900 4500) BN 14
J 2
(-2848 4508);
DISPLAY 0.617021 (-2848 4508);
PAINT PINK (-2848 4508);
FORCEPROP 2 LAST CDS_LIB mstr_standard
J 0
(-2850 4500);
PAINT MONO (-2850 4500);
DISPLAY INVISIBLE (-2850 4500);
FORCEPROP 1 LAST BODY_TYPE PLUMBING
J 2
(-2850 4450);
DISPLAY 1.595745 (-2850 4450);
PAINT GREEN (-2850 4450);
DISPLAY INVISIBLE (-2850 4450);
FORCEPROP 1 LAST HDL_TAP TRUE
J 2
(-3175 4375);
DISPLAY 1.595745 (-3175 4375);
PAINT GREEN (-3175 4375);
DISPLAY INVISIBLE (-3175 4375);
FORCEPROP 1 LAST PATH I167
J 2
(-2848 4500);
DISPLAY 0.872340 (-2848 4500);
PAINT GREEN (-2848 4500);
DISPLAY INVISIBLE (-2848 4500);
FORCEADD TAP..6
R 2
(-2850 4550);
FORCEPROP 3 LASTPIN (-2900 4550) SIG_NAME M_E_DQS_DP<15>
J 0
(-2890 4560);
DISPLAY 0.659574 (-2890 4560);
PAINT MONO (-2890 4560);
DISPLAY INVISIBLE (-2890 4560);
FORCEPROP 1 LASTPIN (-2900 4550) BN 15
J 2
(-2848 4558);
DISPLAY 0.617021 (-2848 4558);
PAINT PINK (-2848 4558);
FORCEPROP 2 LAST CDS_LIB mstr_standard
J 0
(-2850 4550);
PAINT MONO (-2850 4550);
DISPLAY INVISIBLE (-2850 4550);
FORCEPROP 1 LAST BODY_TYPE PLUMBING
J 2
(-2850 4500);
DISPLAY 1.595745 (-2850 4500);
PAINT GREEN (-2850 4500);
DISPLAY INVISIBLE (-2850 4500);
FORCEPROP 1 LAST HDL_TAP TRUE
J 2
(-3175 4425);
DISPLAY 1.595745 (-3175 4425);
PAINT GREEN (-3175 4425);
DISPLAY INVISIBLE (-3175 4425);
FORCEPROP 1 LAST PATH I168
J 2
(-2848 4550);
DISPLAY 0.872340 (-2848 4550);
PAINT GREEN (-2848 4550);
DISPLAY INVISIBLE (-2848 4550);
FORCEADD TAP..6
R 2
(-2850 4600);
FORCEPROP 3 LASTPIN (-2900 4600) SIG_NAME M_E_DQS_DP<16>
J 0
(-2890 4610);
DISPLAY 0.659574 (-2890 4610);
PAINT MONO (-2890 4610);
DISPLAY INVISIBLE (-2890 4610);
FORCEPROP 1 LASTPIN (-2900 4600) BN 16
J 2
(-2848 4608);
DISPLAY 0.617021 (-2848 4608);
PAINT PINK (-2848 4608);
FORCEPROP 2 LAST CDS_LIB mstr_standard
J 0
(-2850 4600);
PAINT MONO (-2850 4600);
DISPLAY INVISIBLE (-2850 4600);
FORCEPROP 1 LAST BODY_TYPE PLUMBING
J 2
(-2850 4550);
DISPLAY 1.595745 (-2850 4550);
PAINT GREEN (-2850 4550);
DISPLAY INVISIBLE (-2850 4550);
FORCEPROP 1 LAST HDL_TAP TRUE
J 2
(-3175 4475);
DISPLAY 1.595745 (-3175 4475);
PAINT GREEN (-3175 4475);
DISPLAY INVISIBLE (-3175 4475);
FORCEPROP 1 LAST PATH I169
J 2
(-2848 4600);
DISPLAY 0.872340 (-2848 4600);
PAINT GREEN (-2848 4600);
DISPLAY INVISIBLE (-2848 4600);
FORCEADD TAP..6
(-5575 1250);
FORCEPROP 3 LASTPIN (-5525 1250) SIG_NAME M_E_ECC<4>
J 0
(-5515 1260);
DISPLAY 0.659574 (-5515 1260);
PAINT MONO (-5515 1260);
DISPLAY INVISIBLE (-5515 1260);
FORCEPROP 1 LASTPIN (-5525 1250) BN 4
J 0
(-5577 1258);
DISPLAY 0.617021 (-5577 1258);
PAINT PINK (-5577 1258);
FORCEPROP 2 LAST CDS_LIB mstr_standard
J 0
(-5575 1250);
PAINT MONO (-5575 1250);
DISPLAY INVISIBLE (-5575 1250);
FORCEPROP 1 LAST BODY_TYPE PLUMBING
J 0
(-5575 1200);
DISPLAY 1.595745 (-5575 1200);
PAINT GREEN (-5575 1200);
DISPLAY INVISIBLE (-5575 1200);
FORCEPROP 1 LAST HDL_TAP TRUE
J 0
(-5250 1125);
DISPLAY 1.595745 (-5250 1125);
PAINT GREEN (-5250 1125);
DISPLAY INVISIBLE (-5250 1125);
FORCEPROP 1 LAST PATH I17
J 0
(-5577 1250);
DISPLAY 0.872340 (-5577 1250);
PAINT GREEN (-5577 1250);
DISPLAY INVISIBLE (-5577 1250);
FORCEADD TAP..6
R 2
(-2850 4650);
FORCEPROP 3 LASTPIN (-2900 4650) SIG_NAME M_E_DQS_DP<17>
J 0
(-2890 4660);
DISPLAY 0.659574 (-2890 4660);
PAINT MONO (-2890 4660);
DISPLAY INVISIBLE (-2890 4660);
FORCEPROP 1 LASTPIN (-2900 4650) BN 17
J 2
(-2848 4658);
DISPLAY 0.617021 (-2848 4658);
PAINT PINK (-2848 4658);
FORCEPROP 2 LAST CDS_LIB mstr_standard
J 2
(-2850 4650);
PAINT MONO (-2850 4650);
DISPLAY INVISIBLE (-2850 4650);
FORCEPROP 1 LAST BODY_TYPE PLUMBING
J 2
(-2850 4600);
DISPLAY 1.595745 (-2850 4600);
PAINT GREEN (-2850 4600);
DISPLAY INVISIBLE (-2850 4600);
FORCEPROP 1 LAST HDL_TAP TRUE
J 2
(-3175 4525);
DISPLAY 1.595745 (-3175 4525);
PAINT GREEN (-3175 4525);
DISPLAY INVISIBLE (-3175 4525);
FORCEPROP 1 LAST PATH I170
J 2
(-2848 4650);
DISPLAY 0.872340 (-2848 4650);
PAINT GREEN (-2848 4650);
DISPLAY INVISIBLE (-2848 4650);
FORCEADD OFFPAGE..3
(-2000 4725);
FORCEPROP 2 LAST $XR1 52 
J 0
(-1696 4725);
DISPLAY 0.638298 (-1696 4725);
PAINT MONO (-1696 4725);
FORCEPROP 2 LAST $XR0 51 
J 0
(-1786 4725);
DISPLAY 0.638298 (-1786 4725);
PAINT MONO (-1786 4725);
FORCEPROP 2 LAST CDS_LIB mstr_standard
J 0
(-2000 4725);
PAINT MONO (-2000 4725);
DISPLAY INVISIBLE (-2000 4725);
FORCEPROP 1 LAST OFFPAGE TRUE
J 0
(-1675 4600);
DISPLAY 1.170213 (-1675 4600);
PAINT GREEN (-1675 4600);
DISPLAY INVISIBLE (-1675 4600);
FORCEPROP 1 LAST COMMENT_BODY TRUE
J 0
(-2050 4625);
DISPLAY 1.170213 (-2050 4625);
PAINT GREEN (-2050 4625);
DISPLAY INVISIBLE (-2050 4625);
FORCEPROP 2 LAST PATH I171
J 0
(-1800 4800);
DISPLAY 1.021277 (-1800 4800);
PAINT ORANGE (-1800 4800);
DISPLAY INVISIBLE (-1800 4800);
FORCEADD SKX_EXT_B..7
(-4175 2550);
FORCEPROP 1 LAST LOCATION U5D1
J 0
(-4975 4900);
DISPLAY 0.617021 (-4975 4900);
PAINT AQUA (-4975 4900);
FORCEPROP 1 LAST PART_NUMBER TBD
J 0
(-4975 300);
DISPLAY 0.617021 (-4975 300);
PAINT BLUE (-4975 300);
FORCEPROP 1 LAST MATERIAL IC
J 0
(-4975 4850);
DISPLAY 0.617021 (-4975 4850);
PAINT SKYBLUE (-4975 4850);
FORCEPROP 2 LASTPIN (-3325 500) $PN DV53
J 0
(-3315 510);
DISPLAY 0.617021 (-3315 510);
PAINT ORANGE (-3315 510);
FORCEPROP 2 LASTPIN (-3325 1550) $PN DM47
J 0
(-3315 1560);
DISPLAY 0.617021 (-3315 1560);
PAINT ORANGE (-3315 1560);
FORCEPROP 2 LASTPIN (-3325 1500) $PN DT49
J 0
(-3315 1510);
DISPLAY 0.617021 (-3315 1510);
PAINT ORANGE (-3315 1510);
FORCEPROP 2 LASTPIN (-3325 1450) $PN DN48
J 0
(-3315 1460);
DISPLAY 0.617021 (-3315 1460);
PAINT ORANGE (-3315 1460);
FORCEPROP 2 LASTPIN (-3325 1400) $PN DR50
J 0
(-3315 1410);
DISPLAY 0.617021 (-3315 1410);
PAINT ORANGE (-3315 1410);
FORCEPROP 2 LASTPIN (-3325 2750) $PN DR48
J 0
(-3315 2760);
DISPLAY 0.617021 (-3315 2760);
PAINT ORANGE (-3315 2760);
FORCEPROP 2 LASTPIN (-3325 2700) $PN DN52
J 0
(-3315 2710);
DISPLAY 0.617021 (-3315 2710);
PAINT ORANGE (-3315 2710);
FORCEPROP 2 LASTPIN (-3325 2650) $PN DR52
J 0
(-3315 2660);
DISPLAY 0.617021 (-3315 2660);
PAINT ORANGE (-3315 2660);
FORCEPROP 2 LASTPIN (-3325 2600) $PN DM51
J 0
(-3315 2610);
DISPLAY 0.617021 (-3315 2610);
PAINT ORANGE (-3315 2610);
FORCEPROP 2 LASTPIN (-3325 2550) $PN DT51
J 0
(-3315 2560);
DISPLAY 0.617021 (-3315 2560);
PAINT ORANGE (-3315 2560);
FORCEPROP 2 LASTPIN (-3325 2500) $PN DN60
J 0
(-3315 2510);
DISPLAY 0.617021 (-3315 2510);
PAINT ORANGE (-3315 2510);
FORCEPROP 2 LASTPIN (-3325 2450) $PN DR60
J 0
(-3315 2460);
DISPLAY 0.617021 (-3315 2460);
PAINT ORANGE (-3315 2460);
FORCEPROP 2 LASTPIN (-3325 2400) $PN DT55
J 0
(-3315 2410);
DISPLAY 0.617021 (-3315 2410);
PAINT ORANGE (-3315 2410);
FORCEPROP 2 LASTPIN (-3325 2350) $PN DV59
J 0
(-3315 2360);
DISPLAY 0.617021 (-3315 2360);
PAINT ORANGE (-3315 2360);
FORCEPROP 2 LASTPIN (-3325 2300) $PN DJ60
J 0
(-3315 2310);
DISPLAY 0.617021 (-3315 2310);
PAINT ORANGE (-3315 2310);
FORCEPROP 2 LASTPIN (-3325 2250) $PN DK61
J 0
(-3315 2260);
DISPLAY 0.617021 (-3315 2260);
PAINT ORANGE (-3315 2260);
FORCEPROP 2 LASTPIN (-3325 2200) $PN DM59
J 0
(-3315 2210);
DISPLAY 0.617021 (-3315 2210);
PAINT ORANGE (-3315 2210);
FORCEPROP 2 LASTPIN (-3325 2150) $PN DN58
J 0
(-3315 2160);
DISPLAY 0.617021 (-3315 2160);
PAINT ORANGE (-3315 2160);
FORCEPROP 2 LASTPIN (-3325 2100) $PN DT59
J 0
(-3315 2110);
DISPLAY 0.617021 (-3315 2110);
PAINT ORANGE (-3315 2110);
FORCEPROP 2 LASTPIN (-3325 2050) $PN DR58
J 0
(-3315 2060);
DISPLAY 0.617021 (-3315 2060);
PAINT ORANGE (-3315 2060);
FORCEPROP 2 LASTPIN (-3325 2000) $PN DV57
J 0
(-3315 2010);
DISPLAY 0.617021 (-3315 2010);
PAINT ORANGE (-3315 2010);
FORCEPROP 2 LASTPIN (-3325 1950) $PN DW58
J 0
(-3315 1960);
DISPLAY 0.617021 (-3315 1960);
PAINT ORANGE (-3315 1960);
FORCEPROP 2 LASTPIN (-3325 1900) $PN DW52
J 0
(-3315 1910);
DISPLAY 0.617021 (-3315 1910);
PAINT ORANGE (-3315 1910);
FORCEPROP 2 LASTPIN (-5025 1400) $PN EA66
J 2
(-5035 1410);
DISPLAY 0.617021 (-5035 1410);
PAINT ORANGE (-5035 1410);
FORCEPROP 2 LASTPIN (-5025 1350) $PN DU66
J 2
(-5035 1360);
DISPLAY 0.617021 (-5035 1360);
PAINT ORANGE (-5035 1360);
FORCEPROP 2 LASTPIN (-5025 1300) $PN DV69
J 2
(-5035 1310);
DISPLAY 0.617021 (-5035 1310);
PAINT ORANGE (-5035 1310);
FORCEPROP 2 LASTPIN (-5025 1250) $PN DU68
J 2
(-5035 1260);
DISPLAY 0.617021 (-5035 1260);
PAINT ORANGE (-5035 1260);
FORCEPROP 2 LASTPIN (-5025 1200) $PN DY65
J 2
(-5035 1210);
DISPLAY 0.617021 (-5035 1210);
PAINT ORANGE (-5035 1210);
FORCEPROP 2 LASTPIN (-5025 1150) $PN DV65
J 2
(-5035 1160);
DISPLAY 0.617021 (-5035 1160);
PAINT ORANGE (-5035 1160);
FORCEPROP 2 LASTPIN (-5025 1050) $PN DY69
J 2
(-5035 1060);
DISPLAY 0.617021 (-5035 1060);
PAINT ORANGE (-5035 1060);
FORCEPROP 2 LASTPIN (-3325 4650) $PN DT67
J 0
(-3315 4660);
DISPLAY 0.617021 (-3315 4660);
PAINT ORANGE (-3315 4660);
FORCEPROP 2 LASTPIN (-3325 4600) $PN DE26
J 0
(-3315 4610);
DISPLAY 0.617021 (-3315 4610);
PAINT ORANGE (-3315 4610);
FORCEPROP 2 LASTPIN (-3325 4550) $PN DW26
J 0
(-3315 4560);
DISPLAY 0.617021 (-3315 4560);
PAINT ORANGE (-3315 4560);
FORCEPROP 2 LASTPIN (-3325 4500) $PN DW32
J 0
(-3315 4510);
DISPLAY 0.617021 (-3315 4510);
PAINT ORANGE (-3315 4510);
FORCEPROP 2 LASTPIN (-3325 4450) $PN DM41
J 0
(-3315 4460);
DISPLAY 0.617021 (-3315 4460);
PAINT ORANGE (-3315 4460);
FORCEPROP 2 LASTPIN (-3325 4400) $PN DY73
J 0
(-3315 4410);
DISPLAY 0.617021 (-3315 4410);
PAINT ORANGE (-3315 4410);
FORCEPROP 2 LASTPIN (-3325 4350) $PN DV79
J 0
(-3315 4360);
DISPLAY 0.617021 (-3315 4360);
PAINT ORANGE (-3315 4360);
FORCEPROP 2 LASTPIN (-3325 4300) $PN DD79
J 0
(-3315 4310);
DISPLAY 0.617021 (-3315 4310);
PAINT ORANGE (-3315 4310);
FORCEPROP 2 LASTPIN (-3325 4250) $PN CP79
J 0
(-3315 4260);
DISPLAY 0.617021 (-3315 4260);
PAINT ORANGE (-3315 4260);
FORCEPROP 2 LASTPIN (-3325 4200) $PN DY67
J 0
(-3315 4210);
DISPLAY 0.617021 (-3315 4210);
PAINT ORANGE (-3315 4210);
FORCEPROP 2 LASTPIN (-3325 4150) $PN DJ26
J 0
(-3315 4160);
DISPLAY 0.617021 (-3315 4160);
PAINT ORANGE (-3315 4160);
FORCEPROP 2 LASTPIN (-3325 4100) $PN EC26
J 0
(-3315 4110);
DISPLAY 0.617021 (-3315 4110);
PAINT ORANGE (-3315 4110);
FORCEPROP 2 LASTPIN (-3325 4050) $PN EC32
J 0
(-3315 4060);
DISPLAY 0.617021 (-3315 4060);
PAINT ORANGE (-3315 4060);
FORCEPROP 2 LASTPIN (-3325 4000) $PN DT41
J 0
(-3315 4010);
DISPLAY 0.617021 (-3315 4010);
PAINT ORANGE (-3315 4010);
FORCEPROP 2 LASTPIN (-3325 3950) $PN ED73
J 0
(-3315 3960);
DISPLAY 0.617021 (-3315 3960);
PAINT ORANGE (-3315 3960);
FORCEPROP 2 LASTPIN (-3325 3900) $PN EB79
J 0
(-3315 3910);
DISPLAY 0.617021 (-3315 3910);
PAINT ORANGE (-3315 3910);
FORCEPROP 2 LASTPIN (-3325 3850) $PN DB81
J 0
(-3315 3860);
DISPLAY 0.617021 (-3315 3860);
PAINT ORANGE (-3315 3860);
FORCEPROP 2 LASTPIN (-3325 3800) $PN CM81
J 0
(-3315 3810);
DISPLAY 0.617021 (-3315 3810);
PAINT ORANGE (-3315 3810);
FORCEPROP 2 LASTPIN (-3325 3700) $PN DV67
J 0
(-3315 3710);
DISPLAY 0.617021 (-3315 3710);
PAINT ORANGE (-3315 3710);
FORCEPROP 2 LASTPIN (-3325 3650) $PN DG26
J 0
(-3315 3660);
DISPLAY 0.617021 (-3315 3660);
PAINT ORANGE (-3315 3660);
FORCEPROP 2 LASTPIN (-3325 3600) $PN EA26
J 0
(-3315 3610);
DISPLAY 0.617021 (-3315 3610);
PAINT ORANGE (-3315 3610);
FORCEPROP 2 LASTPIN (-3325 3550) $PN EA32
J 0
(-3315 3560);
DISPLAY 0.617021 (-3315 3560);
PAINT ORANGE (-3315 3560);
FORCEPROP 2 LASTPIN (-3325 3500) $PN DP41
J 0
(-3315 3510);
DISPLAY 0.617021 (-3315 3510);
PAINT ORANGE (-3315 3510);
FORCEPROP 2 LASTPIN (-3325 3450) $PN EB73
J 0
(-3315 3460);
DISPLAY 0.617021 (-3315 3460);
PAINT ORANGE (-3315 3460);
FORCEPROP 2 LASTPIN (-3325 3400) $PN DY79
J 0
(-3315 3410);
DISPLAY 0.617021 (-3315 3410);
PAINT ORANGE (-3315 3410);
FORCEPROP 2 LASTPIN (-3325 3350) $PN DC80
J 0
(-3315 3360);
DISPLAY 0.617021 (-3315 3360);
PAINT ORANGE (-3315 3360);
FORCEPROP 2 LASTPIN (-3325 3300) $PN CN80
J 0
(-3315 3310);
DISPLAY 0.617021 (-3315 3310);
PAINT ORANGE (-3315 3310);
FORCEPROP 2 LASTPIN (-3325 3250) $PN EB67
J 0
(-3315 3260);
DISPLAY 0.617021 (-3315 3260);
PAINT ORANGE (-3315 3260);
FORCEPROP 2 LASTPIN (-3325 3200) $PN DL26
J 0
(-3315 3210);
DISPLAY 0.617021 (-3315 3210);
PAINT ORANGE (-3315 3210);
FORCEPROP 2 LASTPIN (-3325 3150) $PN EE26
J 0
(-3315 3160);
DISPLAY 0.617021 (-3315 3160);
PAINT ORANGE (-3315 3160);
FORCEPROP 2 LASTPIN (-3325 3100) $PN EE32
J 0
(-3315 3110);
DISPLAY 0.617021 (-3315 3110);
PAINT ORANGE (-3315 3110);
FORCEPROP 2 LASTPIN (-3325 3050) $PN DV41
J 0
(-3315 3060);
DISPLAY 0.617021 (-3315 3060);
PAINT ORANGE (-3315 3060);
FORCEPROP 2 LASTPIN (-3325 3000) $PN EF73
J 0
(-3315 3010);
DISPLAY 0.617021 (-3315 3010);
PAINT ORANGE (-3315 3010);
FORCEPROP 2 LASTPIN (-3325 2950) $PN ED79
J 0
(-3315 2960);
DISPLAY 0.617021 (-3315 2960);
PAINT ORANGE (-3315 2960);
FORCEPROP 2 LASTPIN (-3325 2900) $PN DA82
J 0
(-3315 2910);
DISPLAY 0.617021 (-3315 2910);
PAINT ORANGE (-3315 2910);
FORCEPROP 2 LASTPIN (-3325 2850) $PN CL82
J 0
(-3315 2860);
DISPLAY 0.617021 (-3315 2860);
PAINT ORANGE (-3315 2860);
FORCEPROP 2 LASTPIN (-5025 4650) $PN DK25
J 2
(-5035 4660);
DISPLAY 0.617021 (-5035 4660);
PAINT ORANGE (-5035 4660);
FORCEPROP 2 LASTPIN (-5025 4600) $PN DF25
J 2
(-5035 4610);
DISPLAY 0.617021 (-5035 4610);
PAINT ORANGE (-5035 4610);
FORCEPROP 2 LASTPIN (-5025 4550) $PN DJ28
J 2
(-5035 4560);
DISPLAY 0.617021 (-5035 4560);
PAINT ORANGE (-5035 4560);
FORCEPROP 2 LASTPIN (-5025 4500) $PN DG28
J 2
(-5035 4510);
DISPLAY 0.617021 (-5035 4510);
PAINT ORANGE (-5035 4510);
FORCEPROP 2 LASTPIN (-5025 4450) $PN DJ24
J 2
(-5035 4460);
DISPLAY 0.617021 (-5035 4460);
PAINT ORANGE (-5035 4460);
FORCEPROP 2 LASTPIN (-5025 4400) $PN DD25
J 2
(-5035 4410);
DISPLAY 0.617021 (-5035 4410);
PAINT ORANGE (-5035 4410);
FORCEPROP 2 LASTPIN (-5025 4350) $PN DK27
J 2
(-5035 4360);
DISPLAY 0.617021 (-5035 4360);
PAINT ORANGE (-5035 4360);
FORCEPROP 2 LASTPIN (-5025 4300) $PN DF27
J 2
(-5035 4310);
DISPLAY 0.617021 (-5035 4310);
PAINT ORANGE (-5035 4310);
FORCEPROP 2 LASTPIN (-5025 4250) $PN ED25
J 2
(-5035 4260);
DISPLAY 0.617021 (-5035 4260);
PAINT ORANGE (-5035 4260);
FORCEPROP 2 LASTPIN (-5025 4200) $PN DY25
J 2
(-5035 4210);
DISPLAY 0.617021 (-5035 4210);
PAINT ORANGE (-5035 4210);
FORCEPROP 2 LASTPIN (-5025 4150) $PN EA28
J 2
(-5035 4160);
DISPLAY 0.617021 (-5035 4160);
PAINT ORANGE (-5035 4160);
FORCEPROP 2 LASTPIN (-5025 4100) $PN DY27
J 2
(-5035 4110);
DISPLAY 0.617021 (-5035 4110);
PAINT ORANGE (-5035 4110);
FORCEPROP 2 LASTPIN (-5025 4050) $PN EC24
J 2
(-5035 4060);
DISPLAY 0.617021 (-5035 4060);
PAINT ORANGE (-5035 4060);
FORCEPROP 2 LASTPIN (-5025 4000) $PN EA24
J 2
(-5035 4010);
DISPLAY 0.617021 (-5035 4010);
PAINT ORANGE (-5035 4010);
FORCEPROP 2 LASTPIN (-5025 3950) $PN ED27
J 2
(-5035 3960);
DISPLAY 0.617021 (-5035 3960);
PAINT ORANGE (-5035 3960);
FORCEPROP 2 LASTPIN (-5025 3900) $PN EC28
J 2
(-5035 3910);
DISPLAY 0.617021 (-5035 3910);
PAINT ORANGE (-5035 3910);
FORCEPROP 2 LASTPIN (-5025 3850) $PN ED31
J 2
(-5035 3860);
DISPLAY 0.617021 (-5035 3860);
PAINT ORANGE (-5035 3860);
FORCEPROP 2 LASTPIN (-5025 3800) $PN DY31
J 2
(-5035 3810);
DISPLAY 0.617021 (-5035 3810);
PAINT ORANGE (-5035 3810);
FORCEPROP 2 LASTPIN (-5025 3750) $PN EA34
J 2
(-5035 3760);
DISPLAY 0.617021 (-5035 3760);
PAINT ORANGE (-5035 3760);
FORCEPROP 2 LASTPIN (-5025 3700) $PN DY33
J 2
(-5035 3710);
DISPLAY 0.617021 (-5035 3710);
PAINT ORANGE (-5035 3710);
FORCEPROP 2 LASTPIN (-5025 3650) $PN EC30
J 2
(-5035 3660);
DISPLAY 0.617021 (-5035 3660);
PAINT ORANGE (-5035 3660);
FORCEPROP 2 LASTPIN (-5025 3600) $PN EA30
J 2
(-5035 3610);
DISPLAY 0.617021 (-5035 3610);
PAINT ORANGE (-5035 3610);
FORCEPROP 2 LASTPIN (-5025 3550) $PN ED33
J 2
(-5035 3560);
DISPLAY 0.617021 (-5035 3560);
PAINT ORANGE (-5035 3560);
FORCEPROP 2 LASTPIN (-5025 3500) $PN EC34
J 2
(-5035 3510);
DISPLAY 0.617021 (-5035 3510);
PAINT ORANGE (-5035 3510);
FORCEPROP 2 LASTPIN (-5025 3450) $PN DU40
J 2
(-5035 3460);
DISPLAY 0.617021 (-5035 3460);
PAINT ORANGE (-5035 3460);
FORCEPROP 2 LASTPIN (-5025 3400) $PN DN40
J 2
(-5035 3410);
DISPLAY 0.617021 (-5035 3410);
PAINT ORANGE (-5035 3410);
FORCEPROP 2 LASTPIN (-5025 3350) $PN DN42
J 2
(-5035 3360);
DISPLAY 0.617021 (-5035 3360);
PAINT ORANGE (-5035 3360);
FORCEPROP 2 LASTPIN (-5025 3300) $PN DL42
J 2
(-5035 3310);
DISPLAY 0.617021 (-5035 3310);
PAINT ORANGE (-5035 3310);
FORCEPROP 2 LASTPIN (-5025 3250) $PN DT39
J 2
(-5035 3260);
DISPLAY 0.617021 (-5035 3260);
PAINT ORANGE (-5035 3260);
FORCEPROP 2 LASTPIN (-5025 3200) $PN DP39
J 2
(-5035 3210);
DISPLAY 0.617021 (-5035 3210);
PAINT ORANGE (-5035 3210);
FORCEPROP 2 LASTPIN (-5025 3150) $PN DW42
J 2
(-5035 3160);
DISPLAY 0.617021 (-5035 3160);
PAINT ORANGE (-5035 3160);
FORCEPROP 2 LASTPIN (-5025 3100) $PN DU42
J 2
(-5035 3110);
DISPLAY 0.617021 (-5035 3110);
PAINT ORANGE (-5035 3110);
FORCEPROP 2 LASTPIN (-5025 3050) $PN EE72
J 2
(-5035 3060);
DISPLAY 0.617021 (-5035 3060);
PAINT ORANGE (-5035 3060);
FORCEPROP 2 LASTPIN (-5025 3000) $PN EA72
J 2
(-5035 3010);
DISPLAY 0.617021 (-5035 3010);
PAINT ORANGE (-5035 3010);
FORCEPROP 2 LASTPIN (-5025 2850) $PN ED71
J 2
(-5035 2860);
DISPLAY 0.617021 (-5035 2860);
PAINT ORANGE (-5035 2860);
FORCEPROP 2 LASTPIN (-5025 2800) $PN EB71
J 2
(-5035 2810);
DISPLAY 0.617021 (-5035 2810);
PAINT ORANGE (-5035 2810);
FORCEPROP 2 LASTPIN (-5025 2750) $PN EE74
J 2
(-5035 2760);
DISPLAY 0.617021 (-5035 2760);
PAINT ORANGE (-5035 2760);
FORCEPROP 2 LASTPIN (-5025 2700) $PN ED75
J 2
(-5035 2710);
DISPLAY 0.617021 (-5035 2710);
PAINT ORANGE (-5035 2710);
FORCEPROP 2 LASTPIN (-5025 2650) $PN EC78
J 2
(-5035 2660);
DISPLAY 0.617021 (-5035 2660);
PAINT ORANGE (-5035 2660);
FORCEPROP 2 LASTPIN (-5025 2600) $PN DW78
J 2
(-5035 2610);
DISPLAY 0.617021 (-5035 2610);
PAINT ORANGE (-5035 2610);
FORCEPROP 2 LASTPIN (-5025 2550) $PN EB81
J 2
(-5035 2560);
DISPLAY 0.617021 (-5035 2560);
PAINT ORANGE (-5035 2560);
FORCEPROP 2 LASTPIN (-5025 2500) $PN DY81
J 2
(-5035 2510);
DISPLAY 0.617021 (-5035 2510);
PAINT ORANGE (-5035 2510);
FORCEPROP 2 LASTPIN (-5025 2450) $PN EB77
J 2
(-5035 2460);
DISPLAY 0.617021 (-5035 2460);
PAINT ORANGE (-5035 2460);
FORCEPROP 2 LASTPIN (-5025 2400) $PN DY77
J 2
(-5035 2410);
DISPLAY 0.617021 (-5035 2410);
PAINT ORANGE (-5035 2410);
FORCEPROP 2 LASTPIN (-5025 2350) $PN EC80
J 2
(-5035 2360);
DISPLAY 0.617021 (-5035 2360);
PAINT ORANGE (-5035 2360);
FORCEPROP 2 LASTPIN (-5025 2300) $PN DW80
J 2
(-5035 2310);
DISPLAY 0.617021 (-5035 2310);
PAINT ORANGE (-5035 2310);
FORCEPROP 2 LASTPIN (-5025 2250) $PN DE82
J 2
(-5035 2260);
DISPLAY 0.617021 (-5035 2260);
PAINT ORANGE (-5035 2260);
FORCEPROP 2 LASTPIN (-5025 2200) $PN DC82
J 2
(-5035 2210);
DISPLAY 0.617021 (-5035 2210);
PAINT ORANGE (-5035 2210);
FORCEPROP 2 LASTPIN (-5025 2150) $PN CW80
J 2
(-5035 2160);
DISPLAY 0.617021 (-5035 2160);
PAINT ORANGE (-5035 2160);
FORCEPROP 2 LASTPIN (-5025 2100) $PN CY79
J 2
(-5035 2110);
DISPLAY 0.617021 (-5035 2110);
PAINT ORANGE (-5035 2110);
FORCEPROP 2 LASTPIN (-5025 2050) $PN DF81
J 2
(-5035 2060);
DISPLAY 0.617021 (-5035 2060);
PAINT ORANGE (-5035 2060);
FORCEPROP 2 LASTPIN (-5025 2000) $PN DE80
J 2
(-5035 2010);
DISPLAY 0.617021 (-5035 2010);
PAINT ORANGE (-5035 2010);
FORCEPROP 2 LASTPIN (-5025 1950) $PN CY81
J 2
(-5035 1960);
DISPLAY 0.617021 (-5035 1960);
PAINT ORANGE (-5035 1960);
FORCEPROP 2 LASTPIN (-5025 1900) $PN DB79
J 2
(-5035 1910);
DISPLAY 0.617021 (-5035 1910);
PAINT ORANGE (-5035 1910);
FORCEPROP 2 LASTPIN (-5025 1850) $PN CN82
J 2
(-5035 1860);
DISPLAY 0.617021 (-5035 1860);
PAINT ORANGE (-5035 1860);
FORCEPROP 2 LASTPIN (-5025 1800) $PN CR80
J 2
(-5035 1810);
DISPLAY 0.617021 (-5035 1810);
PAINT ORANGE (-5035 1810);
FORCEPROP 2 LASTPIN (-5025 1750) $PN CJ80
J 2
(-5035 1760);
DISPLAY 0.617021 (-5035 1760);
PAINT ORANGE (-5035 1760);
FORCEPROP 2 LASTPIN (-5025 1700) $PN CK79
J 2
(-5035 1710);
DISPLAY 0.617021 (-5035 1710);
PAINT ORANGE (-5035 1710);
FORCEPROP 2 LASTPIN (-5025 1650) $PN CR82
J 2
(-5035 1660);
DISPLAY 0.617021 (-5035 1660);
PAINT ORANGE (-5035 1660);
FORCEPROP 2 LASTPIN (-5025 1600) $PN CT81
J 2
(-5035 1610);
DISPLAY 0.617021 (-5035 1610);
PAINT ORANGE (-5035 1610);
FORCEPROP 2 LASTPIN (-5025 1550) $PN CK81
J 2
(-5035 1560);
DISPLAY 0.617021 (-5035 1560);
PAINT ORANGE (-5035 1560);
FORCEPROP 2 LASTPIN (-5025 1500) $PN CM79
J 2
(-5035 1510);
DISPLAY 0.617021 (-5035 1510);
PAINT ORANGE (-5035 1510);
FORCEPROP 2 LASTPIN (-3325 1300) $PN DN46
J 0
(-3315 1310);
DISPLAY 0.617021 (-3315 1310);
PAINT ORANGE (-3315 1310);
FORCEPROP 2 LASTPIN (-3325 1250) $PN DT45
J 0
(-3315 1260);
DISPLAY 0.617021 (-3315 1260);
PAINT ORANGE (-3315 1260);
FORCEPROP 2 LASTPIN (-3325 1200) $PN DM49
J 0
(-3315 1210);
DISPLAY 0.617021 (-3315 1210);
PAINT ORANGE (-3315 1210);
FORCEPROP 2 LASTPIN (-3325 1150) $PN DW50
J 0
(-3315 1160);
DISPLAY 0.617021 (-3315 1160);
PAINT ORANGE (-3315 1160);
FORCEPROP 2 LASTPIN (-3325 1100) $PN DK47
J 0
(-3315 1110);
DISPLAY 0.617021 (-3315 1110);
PAINT ORANGE (-3315 1110);
FORCEPROP 2 LASTPIN (-3325 1050) $PN DR46
J 0
(-3315 1060);
DISPLAY 0.617021 (-3315 1060);
PAINT ORANGE (-3315 1060);
FORCEPROP 2 LASTPIN (-3325 1000) $PN DN50
J 0
(-3315 1010);
DISPLAY 0.617021 (-3315 1010);
PAINT ORANGE (-3315 1010);
FORCEPROP 2 LASTPIN (-3325 950) $PN DV51
J 0
(-3315 960);
DISPLAY 0.617021 (-3315 960);
PAINT ORANGE (-3315 960);
FORCEPROP 2 LASTPIN (-5025 950) $PN DR56
J 2
(-5035 960);
DISPLAY 0.617021 (-5035 960);
PAINT ORANGE (-5035 960);
FORCEPROP 2 LASTPIN (-5025 900) $PN DN56
J 2
(-5035 910);
DISPLAY 0.617021 (-5035 910);
PAINT ORANGE (-5035 910);
FORCEPROP 2 LASTPIN (-5025 850) $PN DT53
J 2
(-5035 860);
DISPLAY 0.617021 (-5035 860);
PAINT ORANGE (-5035 860);
FORCEPROP 2 LASTPIN (-5025 800) $PN DN54
J 2
(-5035 810);
DISPLAY 0.617021 (-5035 810);
PAINT ORANGE (-5035 810);
FORCEPROP 2 LASTPIN (-5025 750) $PN DT57
J 2
(-5035 760);
DISPLAY 0.617021 (-5035 760);
PAINT ORANGE (-5035 760);
FORCEPROP 2 LASTPIN (-5025 700) $PN DM57
J 2
(-5035 710);
DISPLAY 0.617021 (-5035 710);
PAINT ORANGE (-5035 710);
FORCEPROP 2 LASTPIN (-5025 650) $PN DR54
J 2
(-5035 660);
DISPLAY 0.617021 (-5035 660);
PAINT ORANGE (-5035 660);
FORCEPROP 2 LASTPIN (-5025 600) $PN DM55
J 2
(-5035 610);
DISPLAY 0.617021 (-5035 610);
PAINT ORANGE (-5035 610);
FORCEPROP 2 LASTPIN (-3325 1800) $PN DR64
J 0
(-3315 1810);
DISPLAY 0.617021 (-3315 1810);
PAINT ORANGE (-3315 1810);
FORCEPROP 2 LASTPIN (-3325 1750) $PN DL64
J 0
(-3315 1760);
DISPLAY 0.617021 (-3315 1760);
PAINT ORANGE (-3315 1760);
FORCEPROP 2 LASTPIN (-3325 1700) $PN DN64
J 0
(-3315 1710);
DISPLAY 0.617021 (-3315 1710);
PAINT ORANGE (-3315 1710);
FORCEPROP 2 LASTPIN (-3325 1650) $PN DM63
J 0
(-3315 1660);
DISPLAY 0.617021 (-3315 1660);
PAINT ORANGE (-3315 1660);
FORCEPROP 2 LASTPIN (-5025 500) $PN DT47
J 2
(-5035 510);
DISPLAY 0.617021 (-5035 510);
PAINT ORANGE (-5035 510);
FORCEPROP 2 LASTPIN (-3325 850) $PN DM61
J 0
(-3315 860);
DISPLAY 0.617021 (-3315 860);
PAINT ORANGE (-3315 860);
FORCEPROP 2 LASTPIN (-3325 800) $PN DJ62
J 0
(-3315 810);
DISPLAY 0.617021 (-3315 810);
PAINT ORANGE (-3315 810);
FORCEPROP 2 LASTPIN (-3325 750) $PN DV55
J 0
(-3315 760);
DISPLAY 0.617021 (-3315 760);
PAINT ORANGE (-3315 760);
FORCEPROP 2 LASTPIN (-3325 700) $PN DM53
J 0
(-3315 710);
DISPLAY 0.617021 (-3315 710);
PAINT ORANGE (-3315 710);
FORCEPROP 2 LASTPIN (-3325 550) $PN DT61
J 0
(-3315 560);
DISPLAY 0.617021 (-3315 560);
PAINT ORANGE (-3315 560);
FORCEPROP 2 LASTPIN (-3325 600) $PN DR62
J 0
(-3315 610);
DISPLAY 0.617021 (-3315 610);
PAINT ORANGE (-3315 610);
FORCEPROP 2 LASTPIN (-5025 2950) $PN EB75
J 2
(-5035 2960);
DISPLAY 0.617021 (-5035 2960);
PAINT ORANGE (-5035 2960);
FORCEPROP 2 LASTPIN (-5025 2900) $PN EA74
J 2
(-5035 2910);
DISPLAY 0.617021 (-5035 2910);
PAINT ORANGE (-5035 2910);
FORCEPROP 2 LASTPIN (-5025 1100) $PN EA68
J 2
(-5035 1110);
DISPLAY 0.617021 (-5035 1110);
PAINT ORANGE (-5035 1110);
FORCEPROP 1 LAST PACK_TYPE BGA1
J 0
(-4975 4950);
PAINT SKYBLUE (-4975 4950);
DISPLAY INVISIBLE (-4975 4950);
FORCEPROP 2 LAST CDS_LIB chpset_lib
J 0
(-4175 2550);
PAINT ORANGE (-4175 2550);
DISPLAY INVISIBLE (-4175 2550);
FORCEPROP 2 LAST SEC_TYPE BGA1
J 0
(-4975 4950);
DISPLAY 1.021277 (-4975 4950);
PAINT ORANGE (-4975 4950);
DISPLAY INVISIBLE (-4975 4950);
FORCEPROP 2 LAST SEC 7
J 0
(-4975 4950);
DISPLAY 0.680851 (-4975 4950);
PAINT MONO (-4975 4950);
DISPLAY INVISIBLE (-4975 4950);
FORCEPROP 2 LAST CDS_LOCATION U5D1
J 0
(-4975 4900);
DISPLAY 0.617021 (-4975 4900);
PAINT AQUA (-4975 4900);
DISPLAY INVISIBLE (-4975 4900);
FORCEPROP 1 LAST PATH I172
J 0
(-4175 4850);
PAINT GREEN (-4175 4850);
DISPLAY INVISIBLE (-4175 4850);
FORCEPROP 0 LAST ROOM CPU0
J 0
(-4975 5000);
DISPLAY 1.021277 (-4975 5000);
PAINT ORANGE (-4975 5000);
DISPLAY INVISIBLE (-4975 5000);
FORCEADD TAP..6
(-5575 1300);
FORCEPROP 3 LASTPIN (-5525 1300) SIG_NAME M_E_ECC<5>
J 0
(-5515 1310);
DISPLAY 0.659574 (-5515 1310);
PAINT MONO (-5515 1310);
DISPLAY INVISIBLE (-5515 1310);
FORCEPROP 1 LASTPIN (-5525 1300) BN 5
J 0
(-5577 1308);
DISPLAY 0.617021 (-5577 1308);
PAINT PINK (-5577 1308);
FORCEPROP 2 LAST CDS_LIB mstr_standard
J 0
(-5575 1300);
PAINT MONO (-5575 1300);
DISPLAY INVISIBLE (-5575 1300);
FORCEPROP 1 LAST BODY_TYPE PLUMBING
J 0
(-5575 1250);
DISPLAY 1.595745 (-5575 1250);
PAINT GREEN (-5575 1250);
DISPLAY INVISIBLE (-5575 1250);
FORCEPROP 1 LAST HDL_TAP TRUE
J 0
(-5250 1175);
DISPLAY 1.595745 (-5250 1175);
PAINT GREEN (-5250 1175);
DISPLAY INVISIBLE (-5250 1175);
FORCEPROP 1 LAST PATH I18
J 0
(-5577 1300);
DISPLAY 0.872340 (-5577 1300);
PAINT GREEN (-5577 1300);
DISPLAY INVISIBLE (-5577 1300);
FORCEADD TAP..6
(-5575 1350);
FORCEPROP 3 LASTPIN (-5525 1350) SIG_NAME M_E_ECC<6>
J 0
(-5515 1360);
DISPLAY 0.659574 (-5515 1360);
PAINT MONO (-5515 1360);
DISPLAY INVISIBLE (-5515 1360);
FORCEPROP 1 LASTPIN (-5525 1350) BN 6
J 0
(-5577 1358);
DISPLAY 0.617021 (-5577 1358);
PAINT PINK (-5577 1358);
FORCEPROP 2 LAST CDS_LIB mstr_standard
J 0
(-5575 1350);
PAINT MONO (-5575 1350);
DISPLAY INVISIBLE (-5575 1350);
FORCEPROP 1 LAST BODY_TYPE PLUMBING
J 0
(-5575 1300);
DISPLAY 1.595745 (-5575 1300);
PAINT GREEN (-5575 1300);
DISPLAY INVISIBLE (-5575 1300);
FORCEPROP 1 LAST HDL_TAP TRUE
J 0
(-5250 1225);
DISPLAY 1.595745 (-5250 1225);
PAINT GREEN (-5250 1225);
DISPLAY INVISIBLE (-5250 1225);
FORCEPROP 1 LAST PATH I19
J 0
(-5577 1350);
DISPLAY 0.872340 (-5577 1350);
PAINT GREEN (-5577 1350);
DISPLAY INVISIBLE (-5577 1350);
FORCEADD OFFPAGE..5
(-6425 800);
FORCEPROP 2 LAST $XR1 52 
J 0
(-6769 800);
DISPLAY 0.638298 (-6769 800);
PAINT MONO (-6769 800);
FORCEPROP 2 LAST $XR0 51 
J 0
(-6679 800);
DISPLAY 0.638298 (-6679 800);
PAINT MONO (-6679 800);
FORCEPROP 2 LAST CDS_LIB mstr_standard
J 0
(-6425 800);
PAINT MONO (-6425 800);
DISPLAY INVISIBLE (-6425 800);
FORCEPROP 1 LAST OFFPAGE TRUE
J 0
(-6100 675);
DISPLAY 1.170213 (-6100 675);
PAINT GREEN (-6100 675);
DISPLAY INVISIBLE (-6100 675);
FORCEPROP 1 LAST COMMENT_BODY TRUE
J 0
(-6325 725);
DISPLAY 1.170213 (-6325 725);
PAINT GREEN (-6325 725);
DISPLAY INVISIBLE (-6325 725);
FORCEPROP 2 LAST PATH I2
J 0
(-6375 875);
DISPLAY 1.021277 (-6375 875);
PAINT ORANGE (-6375 875);
DISPLAY INVISIBLE (-6375 875);
FORCEADD TAP..6
(-5575 1400);
FORCEPROP 3 LASTPIN (-5525 1400) SIG_NAME M_E_ECC<7>
J 0
(-5515 1410);
DISPLAY 0.659574 (-5515 1410);
PAINT MONO (-5515 1410);
DISPLAY INVISIBLE (-5515 1410);
FORCEPROP 1 LASTPIN (-5525 1400) BN 7
J 0
(-5577 1408);
DISPLAY 0.617021 (-5577 1408);
PAINT PINK (-5577 1408);
FORCEPROP 2 LAST CDS_LIB mstr_standard
J 0
(-5575 1400);
PAINT MONO (-5575 1400);
DISPLAY INVISIBLE (-5575 1400);
FORCEPROP 1 LAST BODY_TYPE PLUMBING
J 0
(-5575 1350);
DISPLAY 1.595745 (-5575 1350);
PAINT GREEN (-5575 1350);
DISPLAY INVISIBLE (-5575 1350);
FORCEPROP 1 LAST HDL_TAP TRUE
J 0
(-5250 1275);
DISPLAY 1.595745 (-5250 1275);
PAINT GREEN (-5250 1275);
DISPLAY INVISIBLE (-5250 1275);
FORCEPROP 1 LAST PATH I20
J 0
(-5577 1400);
DISPLAY 0.872340 (-5577 1400);
PAINT GREEN (-5577 1400);
DISPLAY INVISIBLE (-5577 1400);
FORCEADD TAP..6
(-5575 1550);
FORCEPROP 3 LASTPIN (-5525 1550) SIG_NAME M_E_DQ<1>
J 0
(-5515 1560);
DISPLAY 0.659574 (-5515 1560);
PAINT MONO (-5515 1560);
DISPLAY INVISIBLE (-5515 1560);
FORCEPROP 1 LASTPIN (-5525 1550) BN 1
J 0
(-5577 1558);
DISPLAY 0.617021 (-5577 1558);
PAINT PINK (-5577 1558);
FORCEPROP 2 LAST CDS_LIB mstr_standard
J 0
(-5575 1550);
PAINT MONO (-5575 1550);
DISPLAY INVISIBLE (-5575 1550);
FORCEPROP 1 LAST BODY_TYPE PLUMBING
J 0
(-5575 1500);
DISPLAY 1.595745 (-5575 1500);
PAINT GREEN (-5575 1500);
DISPLAY INVISIBLE (-5575 1500);
FORCEPROP 1 LAST HDL_TAP TRUE
J 0
(-5250 1425);
DISPLAY 1.595745 (-5250 1425);
PAINT GREEN (-5250 1425);
DISPLAY INVISIBLE (-5250 1425);
FORCEPROP 1 LAST PATH I21
J 0
(-5577 1550);
DISPLAY 0.872340 (-5577 1550);
PAINT GREEN (-5577 1550);
DISPLAY INVISIBLE (-5577 1550);
FORCEADD TAP..6
(-5575 1500);
FORCEPROP 3 LASTPIN (-5525 1500) SIG_NAME M_E_DQ<0>
J 0
(-5515 1510);
DISPLAY 0.659574 (-5515 1510);
PAINT MONO (-5515 1510);
DISPLAY INVISIBLE (-5515 1510);
FORCEPROP 1 LASTPIN (-5525 1500) BN 0
J 0
(-5577 1508);
DISPLAY 0.617021 (-5577 1508);
PAINT PINK (-5577 1508);
FORCEPROP 2 LAST CDS_LIB mstr_standard
J 0
(-5575 1500);
PAINT MONO (-5575 1500);
DISPLAY INVISIBLE (-5575 1500);
FORCEPROP 1 LAST BODY_TYPE PLUMBING
J 0
(-5575 1450);
DISPLAY 1.595745 (-5575 1450);
PAINT GREEN (-5575 1450);
DISPLAY INVISIBLE (-5575 1450);
FORCEPROP 1 LAST HDL_TAP TRUE
J 0
(-5250 1375);
DISPLAY 1.595745 (-5250 1375);
PAINT GREEN (-5250 1375);
DISPLAY INVISIBLE (-5250 1375);
FORCEPROP 1 LAST PATH I22
J 0
(-5577 1500);
DISPLAY 0.872340 (-5577 1500);
PAINT GREEN (-5577 1500);
DISPLAY INVISIBLE (-5577 1500);
FORCEADD TAP..6
(-5575 1600);
FORCEPROP 3 LASTPIN (-5525 1600) SIG_NAME M_E_DQ<2>
J 0
(-5515 1610);
DISPLAY 0.659574 (-5515 1610);
PAINT MONO (-5515 1610);
DISPLAY INVISIBLE (-5515 1610);
FORCEPROP 1 LASTPIN (-5525 1600) BN 2
J 0
(-5577 1608);
DISPLAY 0.617021 (-5577 1608);
PAINT PINK (-5577 1608);
FORCEPROP 2 LAST CDS_LIB mstr_standard
J 0
(-5575 1600);
PAINT MONO (-5575 1600);
DISPLAY INVISIBLE (-5575 1600);
FORCEPROP 1 LAST BODY_TYPE PLUMBING
J 0
(-5575 1550);
DISPLAY 1.595745 (-5575 1550);
PAINT GREEN (-5575 1550);
DISPLAY INVISIBLE (-5575 1550);
FORCEPROP 1 LAST HDL_TAP TRUE
J 0
(-5250 1475);
DISPLAY 1.595745 (-5250 1475);
PAINT GREEN (-5250 1475);
DISPLAY INVISIBLE (-5250 1475);
FORCEPROP 1 LAST PATH I23
J 0
(-5577 1600);
DISPLAY 0.872340 (-5577 1600);
PAINT GREEN (-5577 1600);
DISPLAY INVISIBLE (-5577 1600);
FORCEADD TAP..6
(-5575 1650);
FORCEPROP 3 LASTPIN (-5525 1650) SIG_NAME M_E_DQ<3>
J 0
(-5515 1660);
DISPLAY 0.659574 (-5515 1660);
PAINT MONO (-5515 1660);
DISPLAY INVISIBLE (-5515 1660);
FORCEPROP 1 LASTPIN (-5525 1650) BN 3
J 0
(-5577 1658);
DISPLAY 0.617021 (-5577 1658);
PAINT PINK (-5577 1658);
FORCEPROP 2 LAST CDS_LIB mstr_standard
J 0
(-5575 1650);
PAINT MONO (-5575 1650);
DISPLAY INVISIBLE (-5575 1650);
FORCEPROP 1 LAST BODY_TYPE PLUMBING
J 0
(-5575 1600);
DISPLAY 1.595745 (-5575 1600);
PAINT GREEN (-5575 1600);
DISPLAY INVISIBLE (-5575 1600);
FORCEPROP 1 LAST HDL_TAP TRUE
J 0
(-5250 1525);
DISPLAY 1.595745 (-5250 1525);
PAINT GREEN (-5250 1525);
DISPLAY INVISIBLE (-5250 1525);
FORCEPROP 1 LAST PATH I24
J 0
(-5577 1650);
DISPLAY 0.872340 (-5577 1650);
PAINT GREEN (-5577 1650);
DISPLAY INVISIBLE (-5577 1650);
FORCEADD TAP..6
(-5575 1700);
FORCEPROP 3 LASTPIN (-5525 1700) SIG_NAME M_E_DQ<4>
J 0
(-5515 1710);
DISPLAY 0.659574 (-5515 1710);
PAINT MONO (-5515 1710);
DISPLAY INVISIBLE (-5515 1710);
FORCEPROP 1 LASTPIN (-5525 1700) BN 4
J 0
(-5577 1708);
DISPLAY 0.617021 (-5577 1708);
PAINT PINK (-5577 1708);
FORCEPROP 2 LAST CDS_LIB mstr_standard
J 0
(-5575 1700);
PAINT MONO (-5575 1700);
DISPLAY INVISIBLE (-5575 1700);
FORCEPROP 1 LAST BODY_TYPE PLUMBING
J 0
(-5575 1650);
DISPLAY 1.595745 (-5575 1650);
PAINT GREEN (-5575 1650);
DISPLAY INVISIBLE (-5575 1650);
FORCEPROP 1 LAST HDL_TAP TRUE
J 0
(-5250 1575);
DISPLAY 1.595745 (-5250 1575);
PAINT GREEN (-5250 1575);
DISPLAY INVISIBLE (-5250 1575);
FORCEPROP 1 LAST PATH I25
J 0
(-5577 1700);
DISPLAY 0.872340 (-5577 1700);
PAINT GREEN (-5577 1700);
DISPLAY INVISIBLE (-5577 1700);
FORCEADD TAP..6
(-5575 1750);
FORCEPROP 3 LASTPIN (-5525 1750) SIG_NAME M_E_DQ<5>
J 0
(-5515 1760);
DISPLAY 0.659574 (-5515 1760);
PAINT MONO (-5515 1760);
DISPLAY INVISIBLE (-5515 1760);
FORCEPROP 1 LASTPIN (-5525 1750) BN 5
J 0
(-5577 1758);
DISPLAY 0.617021 (-5577 1758);
PAINT PINK (-5577 1758);
FORCEPROP 2 LAST CDS_LIB mstr_standard
J 0
(-5575 1750);
PAINT MONO (-5575 1750);
DISPLAY INVISIBLE (-5575 1750);
FORCEPROP 1 LAST BODY_TYPE PLUMBING
J 0
(-5575 1700);
DISPLAY 1.595745 (-5575 1700);
PAINT GREEN (-5575 1700);
DISPLAY INVISIBLE (-5575 1700);
FORCEPROP 1 LAST HDL_TAP TRUE
J 0
(-5250 1625);
DISPLAY 1.595745 (-5250 1625);
PAINT GREEN (-5250 1625);
DISPLAY INVISIBLE (-5250 1625);
FORCEPROP 1 LAST PATH I26
J 0
(-5577 1750);
DISPLAY 0.872340 (-5577 1750);
PAINT GREEN (-5577 1750);
DISPLAY INVISIBLE (-5577 1750);
FORCEADD TAP..6
(-5575 1800);
FORCEPROP 3 LASTPIN (-5525 1800) SIG_NAME M_E_DQ<6>
J 0
(-5515 1810);
DISPLAY 0.659574 (-5515 1810);
PAINT MONO (-5515 1810);
DISPLAY INVISIBLE (-5515 1810);
FORCEPROP 1 LASTPIN (-5525 1800) BN 6
J 0
(-5577 1808);
DISPLAY 0.617021 (-5577 1808);
PAINT PINK (-5577 1808);
FORCEPROP 2 LAST CDS_LIB mstr_standard
J 0
(-5575 1800);
PAINT MONO (-5575 1800);
DISPLAY INVISIBLE (-5575 1800);
FORCEPROP 1 LAST BODY_TYPE PLUMBING
J 0
(-5575 1750);
DISPLAY 1.595745 (-5575 1750);
PAINT GREEN (-5575 1750);
DISPLAY INVISIBLE (-5575 1750);
FORCEPROP 1 LAST HDL_TAP TRUE
J 0
(-5250 1675);
DISPLAY 1.595745 (-5250 1675);
PAINT GREEN (-5250 1675);
DISPLAY INVISIBLE (-5250 1675);
FORCEPROP 1 LAST PATH I27
J 0
(-5577 1800);
DISPLAY 0.872340 (-5577 1800);
PAINT GREEN (-5577 1800);
DISPLAY INVISIBLE (-5577 1800);
FORCEADD TAP..6
(-5575 1900);
FORCEPROP 3 LASTPIN (-5525 1900) SIG_NAME M_E_DQ<8>
J 0
(-5515 1910);
DISPLAY 0.659574 (-5515 1910);
PAINT MONO (-5515 1910);
DISPLAY INVISIBLE (-5515 1910);
FORCEPROP 1 LASTPIN (-5525 1900) BN 8
J 0
(-5577 1908);
DISPLAY 0.617021 (-5577 1908);
PAINT PINK (-5577 1908);
FORCEPROP 2 LAST CDS_LIB mstr_standard
J 0
(-5575 1900);
PAINT MONO (-5575 1900);
DISPLAY INVISIBLE (-5575 1900);
FORCEPROP 1 LAST BODY_TYPE PLUMBING
J 0
(-5575 1850);
DISPLAY 1.595745 (-5575 1850);
PAINT GREEN (-5575 1850);
DISPLAY INVISIBLE (-5575 1850);
FORCEPROP 1 LAST HDL_TAP TRUE
J 0
(-5250 1775);
DISPLAY 1.595745 (-5250 1775);
PAINT GREEN (-5250 1775);
DISPLAY INVISIBLE (-5250 1775);
FORCEPROP 1 LAST PATH I28
J 0
(-5577 1900);
DISPLAY 0.872340 (-5577 1900);
PAINT GREEN (-5577 1900);
DISPLAY INVISIBLE (-5577 1900);
FORCEADD TAP..6
(-5575 1850);
FORCEPROP 3 LASTPIN (-5525 1850) SIG_NAME M_E_DQ<7>
J 0
(-5515 1860);
DISPLAY 0.659574 (-5515 1860);
PAINT MONO (-5515 1860);
DISPLAY INVISIBLE (-5515 1860);
FORCEPROP 1 LASTPIN (-5525 1850) BN 7
J 0
(-5577 1858);
DISPLAY 0.617021 (-5577 1858);
PAINT PINK (-5577 1858);
FORCEPROP 2 LAST CDS_LIB mstr_standard
J 0
(-5575 1850);
PAINT MONO (-5575 1850);
DISPLAY INVISIBLE (-5575 1850);
FORCEPROP 1 LAST BODY_TYPE PLUMBING
J 0
(-5575 1800);
DISPLAY 1.595745 (-5575 1800);
PAINT GREEN (-5575 1800);
DISPLAY INVISIBLE (-5575 1800);
FORCEPROP 1 LAST HDL_TAP TRUE
J 0
(-5250 1725);
DISPLAY 1.595745 (-5250 1725);
PAINT GREEN (-5250 1725);
DISPLAY INVISIBLE (-5250 1725);
FORCEPROP 1 LAST PATH I29
J 0
(-5577 1850);
DISPLAY 0.872340 (-5577 1850);
PAINT GREEN (-5577 1850);
DISPLAY INVISIBLE (-5577 1850);
FORCEADD OFFPAGE..5
(-6425 1000);
FORCEPROP 2 LAST $XR1 52 
J 0
(-6769 1000);
DISPLAY 0.638298 (-6769 1000);
PAINT MONO (-6769 1000);
FORCEPROP 2 LAST $XR0 51 
J 0
(-6679 1000);
DISPLAY 0.638298 (-6679 1000);
PAINT MONO (-6679 1000);
FORCEPROP 2 LAST CDS_LIB mstr_standard
J 0
(-6425 1000);
PAINT MONO (-6425 1000);
DISPLAY INVISIBLE (-6425 1000);
FORCEPROP 1 LAST OFFPAGE TRUE
J 0
(-6100 875);
DISPLAY 1.170213 (-6100 875);
PAINT GREEN (-6100 875);
DISPLAY INVISIBLE (-6100 875);
FORCEPROP 1 LAST COMMENT_BODY TRUE
J 0
(-6325 925);
DISPLAY 1.170213 (-6325 925);
PAINT GREEN (-6325 925);
DISPLAY INVISIBLE (-6325 925);
FORCEPROP 2 LAST PATH I3
J 0
(-6375 1075);
DISPLAY 1.021277 (-6375 1075);
PAINT ORANGE (-6375 1075);
DISPLAY INVISIBLE (-6375 1075);
FORCEADD TAP..6
(-5575 1950);
FORCEPROP 3 LASTPIN (-5525 1950) SIG_NAME M_E_DQ<9>
J 0
(-5515 1960);
DISPLAY 0.659574 (-5515 1960);
PAINT MONO (-5515 1960);
DISPLAY INVISIBLE (-5515 1960);
FORCEPROP 1 LASTPIN (-5525 1950) BN 9
J 0
(-5577 1958);
DISPLAY 0.617021 (-5577 1958);
PAINT PINK (-5577 1958);
FORCEPROP 2 LAST CDS_LIB mstr_standard
J 0
(-5575 1950);
PAINT MONO (-5575 1950);
DISPLAY INVISIBLE (-5575 1950);
FORCEPROP 1 LAST BODY_TYPE PLUMBING
J 0
(-5575 1900);
DISPLAY 1.595745 (-5575 1900);
PAINT GREEN (-5575 1900);
DISPLAY INVISIBLE (-5575 1900);
FORCEPROP 1 LAST HDL_TAP TRUE
J 0
(-5250 1825);
DISPLAY 1.595745 (-5250 1825);
PAINT GREEN (-5250 1825);
DISPLAY INVISIBLE (-5250 1825);
FORCEPROP 1 LAST PATH I30
J 0
(-5577 1950);
DISPLAY 0.872340 (-5577 1950);
PAINT GREEN (-5577 1950);
DISPLAY INVISIBLE (-5577 1950);
FORCEADD TAP..6
(-5575 2000);
FORCEPROP 3 LASTPIN (-5525 2000) SIG_NAME M_E_DQ<10>
J 0
(-5515 2010);
DISPLAY 0.659574 (-5515 2010);
PAINT MONO (-5515 2010);
DISPLAY INVISIBLE (-5515 2010);
FORCEPROP 1 LASTPIN (-5525 2000) BN 10
J 0
(-5577 2008);
DISPLAY 0.617021 (-5577 2008);
PAINT PINK (-5577 2008);
FORCEPROP 2 LAST CDS_LIB mstr_standard
J 0
(-5575 2000);
PAINT MONO (-5575 2000);
DISPLAY INVISIBLE (-5575 2000);
FORCEPROP 1 LAST BODY_TYPE PLUMBING
J 0
(-5575 1950);
DISPLAY 1.595745 (-5575 1950);
PAINT GREEN (-5575 1950);
DISPLAY INVISIBLE (-5575 1950);
FORCEPROP 1 LAST HDL_TAP TRUE
J 0
(-5250 1875);
DISPLAY 1.595745 (-5250 1875);
PAINT GREEN (-5250 1875);
DISPLAY INVISIBLE (-5250 1875);
FORCEPROP 1 LAST PATH I32
J 0
(-5577 2000);
DISPLAY 0.872340 (-5577 2000);
PAINT GREEN (-5577 2000);
DISPLAY INVISIBLE (-5577 2000);
FORCEADD TAP..6
(-5575 2050);
FORCEPROP 3 LASTPIN (-5525 2050) SIG_NAME M_E_DQ<11>
J 0
(-5515 2060);
DISPLAY 0.659574 (-5515 2060);
PAINT MONO (-5515 2060);
DISPLAY INVISIBLE (-5515 2060);
FORCEPROP 1 LASTPIN (-5525 2050) BN 11
J 0
(-5577 2058);
DISPLAY 0.617021 (-5577 2058);
PAINT PINK (-5577 2058);
FORCEPROP 2 LAST CDS_LIB mstr_standard
J 0
(-5575 2050);
PAINT MONO (-5575 2050);
DISPLAY INVISIBLE (-5575 2050);
FORCEPROP 1 LAST BODY_TYPE PLUMBING
J 0
(-5575 2000);
DISPLAY 1.595745 (-5575 2000);
PAINT GREEN (-5575 2000);
DISPLAY INVISIBLE (-5575 2000);
FORCEPROP 1 LAST HDL_TAP TRUE
J 0
(-5250 1925);
DISPLAY 1.595745 (-5250 1925);
PAINT GREEN (-5250 1925);
DISPLAY INVISIBLE (-5250 1925);
FORCEPROP 1 LAST PATH I33
J 0
(-5577 2050);
DISPLAY 0.872340 (-5577 2050);
PAINT GREEN (-5577 2050);
DISPLAY INVISIBLE (-5577 2050);
FORCEADD TAP..6
(-5575 2100);
FORCEPROP 3 LASTPIN (-5525 2100) SIG_NAME M_E_DQ<12>
J 0
(-5515 2110);
DISPLAY 0.659574 (-5515 2110);
PAINT MONO (-5515 2110);
DISPLAY INVISIBLE (-5515 2110);
FORCEPROP 1 LASTPIN (-5525 2100) BN 12
J 0
(-5577 2108);
DISPLAY 0.617021 (-5577 2108);
PAINT PINK (-5577 2108);
FORCEPROP 2 LAST CDS_LIB mstr_standard
J 0
(-5575 2100);
PAINT MONO (-5575 2100);
DISPLAY INVISIBLE (-5575 2100);
FORCEPROP 1 LAST BODY_TYPE PLUMBING
J 0
(-5575 2050);
DISPLAY 1.595745 (-5575 2050);
PAINT GREEN (-5575 2050);
DISPLAY INVISIBLE (-5575 2050);
FORCEPROP 1 LAST HDL_TAP TRUE
J 0
(-5250 1975);
DISPLAY 1.595745 (-5250 1975);
PAINT GREEN (-5250 1975);
DISPLAY INVISIBLE (-5250 1975);
FORCEPROP 1 LAST PATH I34
J 0
(-5577 2100);
DISPLAY 0.872340 (-5577 2100);
PAINT GREEN (-5577 2100);
DISPLAY INVISIBLE (-5577 2100);
FORCEADD TAP..6
(-5575 2150);
FORCEPROP 3 LASTPIN (-5525 2150) SIG_NAME M_E_DQ<13>
J 0
(-5515 2160);
DISPLAY 0.659574 (-5515 2160);
PAINT MONO (-5515 2160);
DISPLAY INVISIBLE (-5515 2160);
FORCEPROP 1 LASTPIN (-5525 2150) BN 13
J 0
(-5577 2158);
DISPLAY 0.617021 (-5577 2158);
PAINT PINK (-5577 2158);
FORCEPROP 2 LAST CDS_LIB mstr_standard
J 0
(-5575 2150);
PAINT MONO (-5575 2150);
DISPLAY INVISIBLE (-5575 2150);
FORCEPROP 1 LAST BODY_TYPE PLUMBING
J 0
(-5575 2100);
DISPLAY 1.595745 (-5575 2100);
PAINT GREEN (-5575 2100);
DISPLAY INVISIBLE (-5575 2100);
FORCEPROP 1 LAST HDL_TAP TRUE
J 0
(-5250 2025);
DISPLAY 1.595745 (-5250 2025);
PAINT GREEN (-5250 2025);
DISPLAY INVISIBLE (-5250 2025);
FORCEPROP 1 LAST PATH I35
J 0
(-5577 2150);
DISPLAY 0.872340 (-5577 2150);
PAINT GREEN (-5577 2150);
DISPLAY INVISIBLE (-5577 2150);
FORCEADD TAP..6
(-5575 2200);
FORCEPROP 3 LASTPIN (-5525 2200) SIG_NAME M_E_DQ<14>
J 0
(-5515 2210);
DISPLAY 0.659574 (-5515 2210);
PAINT MONO (-5515 2210);
DISPLAY INVISIBLE (-5515 2210);
FORCEPROP 1 LASTPIN (-5525 2200) BN 14
J 0
(-5577 2208);
DISPLAY 0.617021 (-5577 2208);
PAINT PINK (-5577 2208);
FORCEPROP 2 LAST CDS_LIB mstr_standard
J 0
(-5575 2200);
PAINT MONO (-5575 2200);
DISPLAY INVISIBLE (-5575 2200);
FORCEPROP 1 LAST BODY_TYPE PLUMBING
J 0
(-5575 2150);
DISPLAY 1.595745 (-5575 2150);
PAINT GREEN (-5575 2150);
DISPLAY INVISIBLE (-5575 2150);
FORCEPROP 1 LAST HDL_TAP TRUE
J 0
(-5250 2075);
DISPLAY 1.595745 (-5250 2075);
PAINT GREEN (-5250 2075);
DISPLAY INVISIBLE (-5250 2075);
FORCEPROP 1 LAST PATH I36
J 0
(-5577 2200);
DISPLAY 0.872340 (-5577 2200);
PAINT GREEN (-5577 2200);
DISPLAY INVISIBLE (-5577 2200);
FORCEADD TAP..6
(-5575 2250);
FORCEPROP 3 LASTPIN (-5525 2250) SIG_NAME M_E_DQ<15>
J 0
(-5515 2260);
DISPLAY 0.659574 (-5515 2260);
PAINT MONO (-5515 2260);
DISPLAY INVISIBLE (-5515 2260);
FORCEPROP 1 LASTPIN (-5525 2250) BN 15
J 0
(-5577 2258);
DISPLAY 0.617021 (-5577 2258);
PAINT PINK (-5577 2258);
FORCEPROP 2 LAST CDS_LIB mstr_standard
J 0
(-5575 2250);
PAINT MONO (-5575 2250);
DISPLAY INVISIBLE (-5575 2250);
FORCEPROP 1 LAST BODY_TYPE PLUMBING
J 0
(-5575 2200);
DISPLAY 1.595745 (-5575 2200);
PAINT GREEN (-5575 2200);
DISPLAY INVISIBLE (-5575 2200);
FORCEPROP 1 LAST HDL_TAP TRUE
J 0
(-5250 2125);
DISPLAY 1.595745 (-5250 2125);
PAINT GREEN (-5250 2125);
DISPLAY INVISIBLE (-5250 2125);
FORCEPROP 1 LAST PATH I37
J 0
(-5577 2250);
DISPLAY 0.872340 (-5577 2250);
PAINT GREEN (-5577 2250);
DISPLAY INVISIBLE (-5577 2250);
FORCEADD TAP..6
(-5575 2300);
FORCEPROP 3 LASTPIN (-5525 2300) SIG_NAME M_E_DQ<16>
J 0
(-5515 2310);
DISPLAY 0.659574 (-5515 2310);
PAINT MONO (-5515 2310);
DISPLAY INVISIBLE (-5515 2310);
FORCEPROP 1 LASTPIN (-5525 2300) BN 16
J 0
(-5577 2308);
DISPLAY 0.617021 (-5577 2308);
PAINT PINK (-5577 2308);
FORCEPROP 2 LAST CDS_LIB mstr_standard
J 0
(-5575 2300);
PAINT MONO (-5575 2300);
DISPLAY INVISIBLE (-5575 2300);
FORCEPROP 1 LAST BODY_TYPE PLUMBING
J 0
(-5575 2250);
DISPLAY 1.595745 (-5575 2250);
PAINT GREEN (-5575 2250);
DISPLAY INVISIBLE (-5575 2250);
FORCEPROP 1 LAST HDL_TAP TRUE
J 0
(-5250 2175);
DISPLAY 1.595745 (-5250 2175);
PAINT GREEN (-5250 2175);
DISPLAY INVISIBLE (-5250 2175);
FORCEPROP 1 LAST PATH I38
J 0
(-5577 2300);
DISPLAY 0.872340 (-5577 2300);
PAINT GREEN (-5577 2300);
DISPLAY INVISIBLE (-5577 2300);
FORCEADD TAP..6
(-5575 2350);
FORCEPROP 3 LASTPIN (-5525 2350) SIG_NAME M_E_DQ<17>
J 0
(-5515 2360);
DISPLAY 0.659574 (-5515 2360);
PAINT MONO (-5515 2360);
DISPLAY INVISIBLE (-5515 2360);
FORCEPROP 1 LASTPIN (-5525 2350) BN 17
J 0
(-5577 2358);
DISPLAY 0.617021 (-5577 2358);
PAINT PINK (-5577 2358);
FORCEPROP 2 LAST CDS_LIB mstr_standard
J 0
(-5575 2350);
PAINT MONO (-5575 2350);
DISPLAY INVISIBLE (-5575 2350);
FORCEPROP 1 LAST BODY_TYPE PLUMBING
J 0
(-5575 2300);
DISPLAY 1.595745 (-5575 2300);
PAINT GREEN (-5575 2300);
DISPLAY INVISIBLE (-5575 2300);
FORCEPROP 1 LAST HDL_TAP TRUE
J 0
(-5250 2225);
DISPLAY 1.595745 (-5250 2225);
PAINT GREEN (-5250 2225);
DISPLAY INVISIBLE (-5250 2225);
FORCEPROP 1 LAST PATH I39
J 0
(-5577 2350);
DISPLAY 0.872340 (-5577 2350);
PAINT GREEN (-5577 2350);
DISPLAY INVISIBLE (-5577 2350);
FORCEADD OFFPAGE..6
(-6425 1450);
FORCEPROP 2 LAST $XR1 52 
J 0
(-6764 1450);
DISPLAY 0.638298 (-6764 1450);
PAINT MONO (-6764 1450);
FORCEPROP 2 LAST $XR0 51 
J 0
(-6674 1450);
DISPLAY 0.638298 (-6674 1450);
PAINT MONO (-6674 1450);
FORCEPROP 2 LAST CDS_LIB mstr_standard
J 0
(-6425 1450);
PAINT MONO (-6425 1450);
DISPLAY INVISIBLE (-6425 1450);
FORCEPROP 1 LAST OFFPAGE TRUE
J 0
(-6100 1325);
DISPLAY 1.170213 (-6100 1325);
PAINT GREEN (-6100 1325);
DISPLAY INVISIBLE (-6100 1325);
FORCEPROP 1 LAST COMMENT_BODY TRUE
J 0
(-6325 1375);
DISPLAY 1.170213 (-6325 1375);
PAINT GREEN (-6325 1375);
DISPLAY INVISIBLE (-6325 1375);
FORCEPROP 2 LAST PATH I4
J 0
(-6375 1525);
DISPLAY 1.021277 (-6375 1525);
PAINT ORANGE (-6375 1525);
DISPLAY INVISIBLE (-6375 1525);
FORCEADD TAP..6
(-5575 2400);
FORCEPROP 3 LASTPIN (-5525 2400) SIG_NAME M_E_DQ<18>
J 0
(-5515 2410);
DISPLAY 0.659574 (-5515 2410);
PAINT MONO (-5515 2410);
DISPLAY INVISIBLE (-5515 2410);
FORCEPROP 1 LASTPIN (-5525 2400) BN 18
J 0
(-5577 2408);
DISPLAY 0.617021 (-5577 2408);
PAINT PINK (-5577 2408);
FORCEPROP 2 LAST CDS_LIB mstr_standard
J 0
(-5575 2400);
PAINT MONO (-5575 2400);
DISPLAY INVISIBLE (-5575 2400);
FORCEPROP 1 LAST BODY_TYPE PLUMBING
J 0
(-5575 2350);
DISPLAY 1.595745 (-5575 2350);
PAINT GREEN (-5575 2350);
DISPLAY INVISIBLE (-5575 2350);
FORCEPROP 1 LAST HDL_TAP TRUE
J 0
(-5250 2275);
DISPLAY 1.595745 (-5250 2275);
PAINT GREEN (-5250 2275);
DISPLAY INVISIBLE (-5250 2275);
FORCEPROP 1 LAST PATH I40
J 0
(-5577 2400);
DISPLAY 0.872340 (-5577 2400);
PAINT GREEN (-5577 2400);
DISPLAY INVISIBLE (-5577 2400);
FORCEADD TAP..6
(-5575 2450);
FORCEPROP 3 LASTPIN (-5525 2450) SIG_NAME M_E_DQ<19>
J 0
(-5515 2460);
DISPLAY 0.659574 (-5515 2460);
PAINT MONO (-5515 2460);
DISPLAY INVISIBLE (-5515 2460);
FORCEPROP 1 LASTPIN (-5525 2450) BN 19
J 0
(-5577 2458);
DISPLAY 0.617021 (-5577 2458);
PAINT PINK (-5577 2458);
FORCEPROP 2 LAST CDS_LIB mstr_standard
J 0
(-5575 2450);
PAINT MONO (-5575 2450);
DISPLAY INVISIBLE (-5575 2450);
FORCEPROP 1 LAST BODY_TYPE PLUMBING
J 0
(-5575 2400);
DISPLAY 1.595745 (-5575 2400);
PAINT GREEN (-5575 2400);
DISPLAY INVISIBLE (-5575 2400);
FORCEPROP 1 LAST HDL_TAP TRUE
J 0
(-5250 2325);
DISPLAY 1.595745 (-5250 2325);
PAINT GREEN (-5250 2325);
DISPLAY INVISIBLE (-5250 2325);
FORCEPROP 1 LAST PATH I41
J 0
(-5577 2450);
DISPLAY 0.872340 (-5577 2450);
PAINT GREEN (-5577 2450);
DISPLAY INVISIBLE (-5577 2450);
FORCEADD TAP..6
(-5575 2500);
FORCEPROP 3 LASTPIN (-5525 2500) SIG_NAME M_E_DQ<20>
J 0
(-5515 2510);
DISPLAY 0.659574 (-5515 2510);
PAINT MONO (-5515 2510);
DISPLAY INVISIBLE (-5515 2510);
FORCEPROP 1 LASTPIN (-5525 2500) BN 20
J 0
(-5577 2508);
DISPLAY 0.617021 (-5577 2508);
PAINT PINK (-5577 2508);
FORCEPROP 2 LAST CDS_LIB mstr_standard
J 0
(-5575 2500);
PAINT MONO (-5575 2500);
DISPLAY INVISIBLE (-5575 2500);
FORCEPROP 1 LAST BODY_TYPE PLUMBING
J 0
(-5575 2450);
DISPLAY 1.595745 (-5575 2450);
PAINT GREEN (-5575 2450);
DISPLAY INVISIBLE (-5575 2450);
FORCEPROP 1 LAST HDL_TAP TRUE
J 0
(-5250 2375);
DISPLAY 1.595745 (-5250 2375);
PAINT GREEN (-5250 2375);
DISPLAY INVISIBLE (-5250 2375);
FORCEPROP 1 LAST PATH I42
J 0
(-5577 2500);
DISPLAY 0.872340 (-5577 2500);
PAINT GREEN (-5577 2500);
DISPLAY INVISIBLE (-5577 2500);
FORCEADD TAP..6
(-5575 2550);
FORCEPROP 3 LASTPIN (-5525 2550) SIG_NAME M_E_DQ<21>
J 0
(-5515 2560);
DISPLAY 0.659574 (-5515 2560);
PAINT MONO (-5515 2560);
DISPLAY INVISIBLE (-5515 2560);
FORCEPROP 1 LASTPIN (-5525 2550) BN 21
J 0
(-5577 2558);
DISPLAY 0.617021 (-5577 2558);
PAINT PINK (-5577 2558);
FORCEPROP 2 LAST CDS_LIB mstr_standard
J 0
(-5575 2550);
PAINT MONO (-5575 2550);
DISPLAY INVISIBLE (-5575 2550);
FORCEPROP 1 LAST BODY_TYPE PLUMBING
J 0
(-5575 2500);
DISPLAY 1.595745 (-5575 2500);
PAINT GREEN (-5575 2500);
DISPLAY INVISIBLE (-5575 2500);
FORCEPROP 1 LAST HDL_TAP TRUE
J 0
(-5250 2425);
DISPLAY 1.595745 (-5250 2425);
PAINT GREEN (-5250 2425);
DISPLAY INVISIBLE (-5250 2425);
FORCEPROP 1 LAST PATH I43
J 0
(-5577 2550);
DISPLAY 0.872340 (-5577 2550);
PAINT GREEN (-5577 2550);
DISPLAY INVISIBLE (-5577 2550);
FORCEADD TAP..6
(-5575 2600);
FORCEPROP 3 LASTPIN (-5525 2600) SIG_NAME M_E_DQ<22>
J 0
(-5515 2610);
DISPLAY 0.659574 (-5515 2610);
PAINT MONO (-5515 2610);
DISPLAY INVISIBLE (-5515 2610);
FORCEPROP 1 LASTPIN (-5525 2600) BN 22
J 0
(-5577 2608);
DISPLAY 0.617021 (-5577 2608);
PAINT PINK (-5577 2608);
FORCEPROP 2 LAST CDS_LIB mstr_standard
J 0
(-5575 2600);
PAINT MONO (-5575 2600);
DISPLAY INVISIBLE (-5575 2600);
FORCEPROP 1 LAST BODY_TYPE PLUMBING
J 0
(-5575 2550);
DISPLAY 1.595745 (-5575 2550);
PAINT GREEN (-5575 2550);
DISPLAY INVISIBLE (-5575 2550);
FORCEPROP 1 LAST HDL_TAP TRUE
J 0
(-5250 2475);
DISPLAY 1.595745 (-5250 2475);
PAINT GREEN (-5250 2475);
DISPLAY INVISIBLE (-5250 2475);
FORCEPROP 1 LAST PATH I44
J 0
(-5577 2600);
DISPLAY 0.872340 (-5577 2600);
PAINT GREEN (-5577 2600);
DISPLAY INVISIBLE (-5577 2600);
FORCEADD TAP..6
(-5575 2650);
FORCEPROP 3 LASTPIN (-5525 2650) SIG_NAME M_E_DQ<23>
J 0
(-5515 2660);
DISPLAY 0.659574 (-5515 2660);
PAINT MONO (-5515 2660);
DISPLAY INVISIBLE (-5515 2660);
FORCEPROP 1 LASTPIN (-5525 2650) BN 23
J 0
(-5577 2658);
DISPLAY 0.617021 (-5577 2658);
PAINT PINK (-5577 2658);
FORCEPROP 2 LAST CDS_LIB mstr_standard
J 0
(-5575 2650);
PAINT MONO (-5575 2650);
DISPLAY INVISIBLE (-5575 2650);
FORCEPROP 1 LAST BODY_TYPE PLUMBING
J 0
(-5575 2600);
DISPLAY 1.595745 (-5575 2600);
PAINT GREEN (-5575 2600);
DISPLAY INVISIBLE (-5575 2600);
FORCEPROP 1 LAST HDL_TAP TRUE
J 0
(-5250 2525);
DISPLAY 1.595745 (-5250 2525);
PAINT GREEN (-5250 2525);
DISPLAY INVISIBLE (-5250 2525);
FORCEPROP 1 LAST PATH I45
J 0
(-5577 2650);
DISPLAY 0.872340 (-5577 2650);
PAINT GREEN (-5577 2650);
DISPLAY INVISIBLE (-5577 2650);
FORCEADD TAP..6
(-5575 2700);
FORCEPROP 3 LASTPIN (-5525 2700) SIG_NAME M_E_DQ<24>
J 0
(-5515 2710);
DISPLAY 0.659574 (-5515 2710);
PAINT MONO (-5515 2710);
DISPLAY INVISIBLE (-5515 2710);
FORCEPROP 1 LASTPIN (-5525 2700) BN 24
J 0
(-5577 2708);
DISPLAY 0.617021 (-5577 2708);
PAINT PINK (-5577 2708);
FORCEPROP 2 LAST CDS_LIB mstr_standard
J 0
(-5575 2700);
PAINT MONO (-5575 2700);
DISPLAY INVISIBLE (-5575 2700);
FORCEPROP 1 LAST BODY_TYPE PLUMBING
J 0
(-5575 2650);
DISPLAY 1.595745 (-5575 2650);
PAINT GREEN (-5575 2650);
DISPLAY INVISIBLE (-5575 2650);
FORCEPROP 1 LAST HDL_TAP TRUE
J 0
(-5250 2575);
DISPLAY 1.595745 (-5250 2575);
PAINT GREEN (-5250 2575);
DISPLAY INVISIBLE (-5250 2575);
FORCEPROP 1 LAST PATH I46
J 0
(-5577 2700);
DISPLAY 0.872340 (-5577 2700);
PAINT GREEN (-5577 2700);
DISPLAY INVISIBLE (-5577 2700);
FORCEADD TAP..6
(-5575 2800);
FORCEPROP 3 LASTPIN (-5525 2800) SIG_NAME M_E_DQ<26>
J 0
(-5515 2810);
DISPLAY 0.659574 (-5515 2810);
PAINT MONO (-5515 2810);
DISPLAY INVISIBLE (-5515 2810);
FORCEPROP 1 LASTPIN (-5525 2800) BN 26
J 0
(-5577 2808);
DISPLAY 0.617021 (-5577 2808);
PAINT PINK (-5577 2808);
FORCEPROP 2 LAST CDS_LIB mstr_standard
J 0
(-5575 2800);
PAINT MONO (-5575 2800);
DISPLAY INVISIBLE (-5575 2800);
FORCEPROP 1 LAST BODY_TYPE PLUMBING
J 0
(-5575 2750);
DISPLAY 1.595745 (-5575 2750);
PAINT GREEN (-5575 2750);
DISPLAY INVISIBLE (-5575 2750);
FORCEPROP 1 LAST HDL_TAP TRUE
J 0
(-5250 2675);
DISPLAY 1.595745 (-5250 2675);
PAINT GREEN (-5250 2675);
DISPLAY INVISIBLE (-5250 2675);
FORCEPROP 1 LAST PATH I47
J 0
(-5577 2800);
DISPLAY 0.872340 (-5577 2800);
PAINT GREEN (-5577 2800);
DISPLAY INVISIBLE (-5577 2800);
FORCEADD TAP..6
(-5575 2750);
FORCEPROP 3 LASTPIN (-5525 2750) SIG_NAME M_E_DQ<25>
J 0
(-5515 2760);
DISPLAY 0.659574 (-5515 2760);
PAINT MONO (-5515 2760);
DISPLAY INVISIBLE (-5515 2760);
FORCEPROP 1 LASTPIN (-5525 2750) BN 25
J 0
(-5577 2758);
DISPLAY 0.617021 (-5577 2758);
PAINT PINK (-5577 2758);
FORCEPROP 2 LAST CDS_LIB mstr_standard
J 0
(-5575 2750);
PAINT MONO (-5575 2750);
DISPLAY INVISIBLE (-5575 2750);
FORCEPROP 1 LAST BODY_TYPE PLUMBING
J 0
(-5575 2700);
DISPLAY 1.595745 (-5575 2700);
PAINT GREEN (-5575 2700);
DISPLAY INVISIBLE (-5575 2700);
FORCEPROP 1 LAST HDL_TAP TRUE
J 0
(-5250 2625);
DISPLAY 1.595745 (-5250 2625);
PAINT GREEN (-5250 2625);
DISPLAY INVISIBLE (-5250 2625);
FORCEPROP 1 LAST PATH I48
J 0
(-5577 2750);
DISPLAY 0.872340 (-5577 2750);
PAINT GREEN (-5577 2750);
DISPLAY INVISIBLE (-5577 2750);
FORCEADD TAP..6
(-5575 2850);
FORCEPROP 3 LASTPIN (-5525 2850) SIG_NAME M_E_DQ<27>
J 0
(-5515 2860);
DISPLAY 0.659574 (-5515 2860);
PAINT MONO (-5515 2860);
DISPLAY INVISIBLE (-5515 2860);
FORCEPROP 1 LASTPIN (-5525 2850) BN 27
J 0
(-5577 2858);
DISPLAY 0.617021 (-5577 2858);
PAINT PINK (-5577 2858);
FORCEPROP 2 LAST CDS_LIB mstr_standard
J 0
(-5575 2850);
PAINT MONO (-5575 2850);
DISPLAY INVISIBLE (-5575 2850);
FORCEPROP 1 LAST BODY_TYPE PLUMBING
J 0
(-5575 2800);
DISPLAY 1.595745 (-5575 2800);
PAINT GREEN (-5575 2800);
DISPLAY INVISIBLE (-5575 2800);
FORCEPROP 1 LAST HDL_TAP TRUE
J 0
(-5250 2725);
DISPLAY 1.595745 (-5250 2725);
PAINT GREEN (-5250 2725);
DISPLAY INVISIBLE (-5250 2725);
FORCEPROP 1 LAST PATH I49
J 0
(-5577 2850);
DISPLAY 0.872340 (-5577 2850);
PAINT GREEN (-5577 2850);
DISPLAY INVISIBLE (-5577 2850);
FORCEADD TAP..6
(-5575 600);
FORCEPROP 3 LASTPIN (-5525 600) SIG_NAME M_E_CLK_DN<0>
J 0
(-5515 610);
DISPLAY 0.659574 (-5515 610);
PAINT MONO (-5515 610);
DISPLAY INVISIBLE (-5515 610);
FORCEPROP 1 LASTPIN (-5525 600) BN 0
J 0
(-5577 608);
DISPLAY 0.617021 (-5577 608);
PAINT PINK (-5577 608);
FORCEPROP 2 LAST CDS_LIB mstr_standard
J 0
(-5575 600);
PAINT MONO (-5575 600);
DISPLAY INVISIBLE (-5575 600);
FORCEPROP 1 LAST BODY_TYPE PLUMBING
J 0
(-5575 550);
DISPLAY 1.595745 (-5575 550);
PAINT GREEN (-5575 550);
DISPLAY INVISIBLE (-5575 550);
FORCEPROP 1 LAST HDL_TAP TRUE
J 0
(-5250 475);
DISPLAY 1.595745 (-5250 475);
PAINT GREEN (-5250 475);
DISPLAY INVISIBLE (-5250 475);
FORCEPROP 1 LAST PATH I5
J 0
(-5577 600);
DISPLAY 0.872340 (-5577 600);
PAINT GREEN (-5577 600);
DISPLAY INVISIBLE (-5577 600);
FORCEADD TAP..6
(-5575 2900);
FORCEPROP 3 LASTPIN (-5525 2900) SIG_NAME M_E_DQ<28>
J 0
(-5515 2910);
DISPLAY 0.659574 (-5515 2910);
PAINT MONO (-5515 2910);
DISPLAY INVISIBLE (-5515 2910);
FORCEPROP 1 LASTPIN (-5525 2900) BN 28
J 0
(-5577 2908);
DISPLAY 0.617021 (-5577 2908);
PAINT PINK (-5577 2908);
FORCEPROP 2 LAST CDS_LIB mstr_standard
J 0
(-5575 2900);
PAINT MONO (-5575 2900);
DISPLAY INVISIBLE (-5575 2900);
FORCEPROP 1 LAST BODY_TYPE PLUMBING
J 0
(-5575 2850);
DISPLAY 1.595745 (-5575 2850);
PAINT GREEN (-5575 2850);
DISPLAY INVISIBLE (-5575 2850);
FORCEPROP 1 LAST HDL_TAP TRUE
J 0
(-5250 2775);
DISPLAY 1.595745 (-5250 2775);
PAINT GREEN (-5250 2775);
DISPLAY INVISIBLE (-5250 2775);
FORCEPROP 1 LAST PATH I50
J 0
(-5577 2900);
DISPLAY 0.872340 (-5577 2900);
PAINT GREEN (-5577 2900);
DISPLAY INVISIBLE (-5577 2900);
FORCEADD TAP..6
(-5575 2950);
FORCEPROP 3 LASTPIN (-5525 2950) SIG_NAME M_E_DQ<29>
J 0
(-5515 2960);
DISPLAY 0.659574 (-5515 2960);
PAINT MONO (-5515 2960);
DISPLAY INVISIBLE (-5515 2960);
FORCEPROP 1 LASTPIN (-5525 2950) BN 29
J 0
(-5577 2958);
DISPLAY 0.617021 (-5577 2958);
PAINT PINK (-5577 2958);
FORCEPROP 2 LAST CDS_LIB mstr_standard
J 0
(-5575 2950);
PAINT MONO (-5575 2950);
DISPLAY INVISIBLE (-5575 2950);
FORCEPROP 1 LAST BODY_TYPE PLUMBING
J 0
(-5575 2900);
DISPLAY 1.595745 (-5575 2900);
PAINT GREEN (-5575 2900);
DISPLAY INVISIBLE (-5575 2900);
FORCEPROP 1 LAST HDL_TAP TRUE
J 0
(-5250 2825);
DISPLAY 1.595745 (-5250 2825);
PAINT GREEN (-5250 2825);
DISPLAY INVISIBLE (-5250 2825);
FORCEPROP 1 LAST PATH I51
J 0
(-5577 2950);
DISPLAY 0.872340 (-5577 2950);
PAINT GREEN (-5577 2950);
DISPLAY INVISIBLE (-5577 2950);
FORCEADD TAP..6
(-5575 3050);
FORCEPROP 3 LASTPIN (-5525 3050) SIG_NAME M_E_DQ<31>
J 0
(-5515 3060);
DISPLAY 0.659574 (-5515 3060);
PAINT MONO (-5515 3060);
DISPLAY INVISIBLE (-5515 3060);
FORCEPROP 1 LASTPIN (-5525 3050) BN 31
J 0
(-5577 3058);
DISPLAY 0.617021 (-5577 3058);
PAINT PINK (-5577 3058);
FORCEPROP 2 LAST CDS_LIB mstr_standard
J 0
(-5575 3050);
PAINT MONO (-5575 3050);
DISPLAY INVISIBLE (-5575 3050);
FORCEPROP 1 LAST BODY_TYPE PLUMBING
J 0
(-5575 3000);
DISPLAY 1.595745 (-5575 3000);
PAINT GREEN (-5575 3000);
DISPLAY INVISIBLE (-5575 3000);
FORCEPROP 1 LAST HDL_TAP TRUE
J 0
(-5250 2925);
DISPLAY 1.595745 (-5250 2925);
PAINT GREEN (-5250 2925);
DISPLAY INVISIBLE (-5250 2925);
FORCEPROP 1 LAST PATH I52
J 0
(-5577 3050);
DISPLAY 0.872340 (-5577 3050);
PAINT GREEN (-5577 3050);
DISPLAY INVISIBLE (-5577 3050);
FORCEADD TAP..6
(-5575 3000);
FORCEPROP 3 LASTPIN (-5525 3000) SIG_NAME M_E_DQ<30>
J 0
(-5515 3010);
DISPLAY 0.659574 (-5515 3010);
PAINT MONO (-5515 3010);
DISPLAY INVISIBLE (-5515 3010);
FORCEPROP 1 LASTPIN (-5525 3000) BN 30
J 0
(-5577 3008);
DISPLAY 0.617021 (-5577 3008);
PAINT PINK (-5577 3008);
FORCEPROP 2 LAST CDS_LIB mstr_standard
J 0
(-5575 3000);
PAINT MONO (-5575 3000);
DISPLAY INVISIBLE (-5575 3000);
FORCEPROP 1 LAST BODY_TYPE PLUMBING
J 0
(-5575 2950);
DISPLAY 1.595745 (-5575 2950);
PAINT GREEN (-5575 2950);
DISPLAY INVISIBLE (-5575 2950);
FORCEPROP 1 LAST HDL_TAP TRUE
J 0
(-5250 2875);
DISPLAY 1.595745 (-5250 2875);
PAINT GREEN (-5250 2875);
DISPLAY INVISIBLE (-5250 2875);
FORCEPROP 1 LAST PATH I53
J 0
(-5577 3000);
DISPLAY 0.872340 (-5577 3000);
PAINT GREEN (-5577 3000);
DISPLAY INVISIBLE (-5577 3000);
FORCEADD TAP..6
(-5575 3100);
FORCEPROP 3 LASTPIN (-5525 3100) SIG_NAME M_E_DQ<32>
J 0
(-5515 3110);
DISPLAY 0.659574 (-5515 3110);
PAINT MONO (-5515 3110);
DISPLAY INVISIBLE (-5515 3110);
FORCEPROP 1 LASTPIN (-5525 3100) BN 32
J 0
(-5577 3108);
DISPLAY 0.617021 (-5577 3108);
PAINT PINK (-5577 3108);
FORCEPROP 2 LAST CDS_LIB mstr_standard
J 0
(-5575 3100);
PAINT MONO (-5575 3100);
DISPLAY INVISIBLE (-5575 3100);
FORCEPROP 1 LAST BODY_TYPE PLUMBING
J 0
(-5575 3050);
DISPLAY 1.595745 (-5575 3050);
PAINT GREEN (-5575 3050);
DISPLAY INVISIBLE (-5575 3050);
FORCEPROP 1 LAST HDL_TAP TRUE
J 0
(-5250 2975);
DISPLAY 1.595745 (-5250 2975);
PAINT GREEN (-5250 2975);
DISPLAY INVISIBLE (-5250 2975);
FORCEPROP 1 LAST PATH I54
J 0
(-5577 3100);
DISPLAY 0.872340 (-5577 3100);
PAINT GREEN (-5577 3100);
DISPLAY INVISIBLE (-5577 3100);
FORCEADD TAP..6
(-5575 3150);
FORCEPROP 3 LASTPIN (-5525 3150) SIG_NAME M_E_DQ<33>
J 0
(-5515 3160);
DISPLAY 0.659574 (-5515 3160);
PAINT MONO (-5515 3160);
DISPLAY INVISIBLE (-5515 3160);
FORCEPROP 1 LASTPIN (-5525 3150) BN 33
J 0
(-5577 3158);
DISPLAY 0.617021 (-5577 3158);
PAINT PINK (-5577 3158);
FORCEPROP 2 LAST CDS_LIB mstr_standard
J 0
(-5575 3150);
PAINT MONO (-5575 3150);
DISPLAY INVISIBLE (-5575 3150);
FORCEPROP 1 LAST BODY_TYPE PLUMBING
J 0
(-5575 3100);
DISPLAY 1.595745 (-5575 3100);
PAINT GREEN (-5575 3100);
DISPLAY INVISIBLE (-5575 3100);
FORCEPROP 1 LAST HDL_TAP TRUE
J 0
(-5250 3025);
DISPLAY 1.595745 (-5250 3025);
PAINT GREEN (-5250 3025);
DISPLAY INVISIBLE (-5250 3025);
FORCEPROP 1 LAST PATH I55
J 0
(-5577 3150);
DISPLAY 0.872340 (-5577 3150);
PAINT GREEN (-5577 3150);
DISPLAY INVISIBLE (-5577 3150);
FORCEADD TAP..6
(-5575 3200);
FORCEPROP 3 LASTPIN (-5525 3200) SIG_NAME M_E_DQ<34>
J 0
(-5515 3210);
DISPLAY 0.659574 (-5515 3210);
PAINT MONO (-5515 3210);
DISPLAY INVISIBLE (-5515 3210);
FORCEPROP 1 LASTPIN (-5525 3200) BN 34
J 0
(-5577 3208);
DISPLAY 0.617021 (-5577 3208);
PAINT PINK (-5577 3208);
FORCEPROP 2 LAST CDS_LIB mstr_standard
J 0
(-5575 3200);
PAINT MONO (-5575 3200);
DISPLAY INVISIBLE (-5575 3200);
FORCEPROP 1 LAST BODY_TYPE PLUMBING
J 0
(-5575 3150);
DISPLAY 1.595745 (-5575 3150);
PAINT GREEN (-5575 3150);
DISPLAY INVISIBLE (-5575 3150);
FORCEPROP 1 LAST HDL_TAP TRUE
J 0
(-5250 3075);
DISPLAY 1.595745 (-5250 3075);
PAINT GREEN (-5250 3075);
DISPLAY INVISIBLE (-5250 3075);
FORCEPROP 1 LAST PATH I56
J 0
(-5577 3200);
DISPLAY 0.872340 (-5577 3200);
PAINT GREEN (-5577 3200);
DISPLAY INVISIBLE (-5577 3200);
FORCEADD TAP..6
(-5575 3250);
FORCEPROP 3 LASTPIN (-5525 3250) SIG_NAME M_E_DQ<35>
J 0
(-5515 3260);
DISPLAY 0.659574 (-5515 3260);
PAINT MONO (-5515 3260);
DISPLAY INVISIBLE (-5515 3260);
FORCEPROP 1 LASTPIN (-5525 3250) BN 35
J 0
(-5577 3258);
DISPLAY 0.617021 (-5577 3258);
PAINT PINK (-5577 3258);
FORCEPROP 2 LAST CDS_LIB mstr_standard
J 0
(-5575 3250);
PAINT MONO (-5575 3250);
DISPLAY INVISIBLE (-5575 3250);
FORCEPROP 1 LAST BODY_TYPE PLUMBING
J 0
(-5575 3200);
DISPLAY 1.595745 (-5575 3200);
PAINT GREEN (-5575 3200);
DISPLAY INVISIBLE (-5575 3200);
FORCEPROP 1 LAST HDL_TAP TRUE
J 0
(-5250 3125);
DISPLAY 1.595745 (-5250 3125);
PAINT GREEN (-5250 3125);
DISPLAY INVISIBLE (-5250 3125);
FORCEPROP 1 LAST PATH I57
J 0
(-5577 3250);
DISPLAY 0.872340 (-5577 3250);
PAINT GREEN (-5577 3250);
DISPLAY INVISIBLE (-5577 3250);
FORCEADD TAP..6
(-5575 3300);
FORCEPROP 3 LASTPIN (-5525 3300) SIG_NAME M_E_DQ<36>
J 0
(-5515 3310);
DISPLAY 0.659574 (-5515 3310);
PAINT MONO (-5515 3310);
DISPLAY INVISIBLE (-5515 3310);
FORCEPROP 1 LASTPIN (-5525 3300) BN 36
J 0
(-5577 3308);
DISPLAY 0.617021 (-5577 3308);
PAINT PINK (-5577 3308);
FORCEPROP 2 LAST CDS_LIB mstr_standard
J 0
(-5575 3300);
PAINT MONO (-5575 3300);
DISPLAY INVISIBLE (-5575 3300);
FORCEPROP 1 LAST BODY_TYPE PLUMBING
J 0
(-5575 3250);
DISPLAY 1.595745 (-5575 3250);
PAINT GREEN (-5575 3250);
DISPLAY INVISIBLE (-5575 3250);
FORCEPROP 1 LAST HDL_TAP TRUE
J 0
(-5250 3175);
DISPLAY 1.595745 (-5250 3175);
PAINT GREEN (-5250 3175);
DISPLAY INVISIBLE (-5250 3175);
FORCEPROP 1 LAST PATH I58
J 0
(-5577 3300);
DISPLAY 0.872340 (-5577 3300);
PAINT GREEN (-5577 3300);
DISPLAY INVISIBLE (-5577 3300);
FORCEADD TAP..6
(-5575 3350);
FORCEPROP 3 LASTPIN (-5525 3350) SIG_NAME M_E_DQ<37>
J 0
(-5515 3360);
DISPLAY 0.659574 (-5515 3360);
PAINT MONO (-5515 3360);
DISPLAY INVISIBLE (-5515 3360);
FORCEPROP 1 LASTPIN (-5525 3350) BN 37
J 0
(-5577 3358);
DISPLAY 0.617021 (-5577 3358);
PAINT PINK (-5577 3358);
FORCEPROP 2 LAST CDS_LIB mstr_standard
J 0
(-5575 3350);
PAINT MONO (-5575 3350);
DISPLAY INVISIBLE (-5575 3350);
FORCEPROP 1 LAST BODY_TYPE PLUMBING
J 0
(-5575 3300);
DISPLAY 1.595745 (-5575 3300);
PAINT GREEN (-5575 3300);
DISPLAY INVISIBLE (-5575 3300);
FORCEPROP 1 LAST HDL_TAP TRUE
J 0
(-5250 3225);
DISPLAY 1.595745 (-5250 3225);
PAINT GREEN (-5250 3225);
DISPLAY INVISIBLE (-5250 3225);
FORCEPROP 1 LAST PATH I59
J 0
(-5577 3350);
DISPLAY 0.872340 (-5577 3350);
PAINT GREEN (-5577 3350);
DISPLAY INVISIBLE (-5577 3350);
FORCEADD TAP..6
(-5575 650);
FORCEPROP 3 LASTPIN (-5525 650) SIG_NAME M_E_CLK_DN<1>
J 0
(-5515 660);
DISPLAY 0.659574 (-5515 660);
PAINT MONO (-5515 660);
DISPLAY INVISIBLE (-5515 660);
FORCEPROP 1 LASTPIN (-5525 650) BN 1
J 0
(-5577 658);
DISPLAY 0.617021 (-5577 658);
PAINT PINK (-5577 658);
FORCEPROP 2 LAST CDS_LIB mstr_standard
J 0
(-5575 650);
PAINT MONO (-5575 650);
DISPLAY INVISIBLE (-5575 650);
FORCEPROP 1 LAST BODY_TYPE PLUMBING
J 0
(-5575 600);
DISPLAY 1.595745 (-5575 600);
PAINT GREEN (-5575 600);
DISPLAY INVISIBLE (-5575 600);
FORCEPROP 1 LAST HDL_TAP TRUE
J 0
(-5250 525);
DISPLAY 1.595745 (-5250 525);
PAINT GREEN (-5250 525);
DISPLAY INVISIBLE (-5250 525);
FORCEPROP 1 LAST PATH I6
J 0
(-5577 650);
DISPLAY 0.872340 (-5577 650);
PAINT GREEN (-5577 650);
DISPLAY INVISIBLE (-5577 650);
FORCEADD TAP..6
(-5575 3400);
FORCEPROP 3 LASTPIN (-5525 3400) SIG_NAME M_E_DQ<38>
J 0
(-5515 3410);
DISPLAY 0.659574 (-5515 3410);
PAINT MONO (-5515 3410);
DISPLAY INVISIBLE (-5515 3410);
FORCEPROP 1 LASTPIN (-5525 3400) BN 38
J 0
(-5577 3408);
DISPLAY 0.617021 (-5577 3408);
PAINT PINK (-5577 3408);
FORCEPROP 2 LAST CDS_LIB mstr_standard
J 0
(-5575 3400);
PAINT MONO (-5575 3400);
DISPLAY INVISIBLE (-5575 3400);
FORCEPROP 1 LAST BODY_TYPE PLUMBING
J 0
(-5575 3350);
DISPLAY 1.595745 (-5575 3350);
PAINT GREEN (-5575 3350);
DISPLAY INVISIBLE (-5575 3350);
FORCEPROP 1 LAST HDL_TAP TRUE
J 0
(-5250 3275);
DISPLAY 1.595745 (-5250 3275);
PAINT GREEN (-5250 3275);
DISPLAY INVISIBLE (-5250 3275);
FORCEPROP 1 LAST PATH I60
J 0
(-5577 3400);
DISPLAY 0.872340 (-5577 3400);
PAINT GREEN (-5577 3400);
DISPLAY INVISIBLE (-5577 3400);
FORCEADD TAP..6
(-5575 3450);
FORCEPROP 3 LASTPIN (-5525 3450) SIG_NAME M_E_DQ<39>
J 0
(-5515 3460);
DISPLAY 0.659574 (-5515 3460);
PAINT MONO (-5515 3460);
DISPLAY INVISIBLE (-5515 3460);
FORCEPROP 1 LASTPIN (-5525 3450) BN 39
J 0
(-5577 3458);
DISPLAY 0.617021 (-5577 3458);
PAINT PINK (-5577 3458);
FORCEPROP 2 LAST CDS_LIB mstr_standard
J 0
(-5575 3450);
PAINT MONO (-5575 3450);
DISPLAY INVISIBLE (-5575 3450);
FORCEPROP 1 LAST BODY_TYPE PLUMBING
J 0
(-5575 3400);
DISPLAY 1.595745 (-5575 3400);
PAINT GREEN (-5575 3400);
DISPLAY INVISIBLE (-5575 3400);
FORCEPROP 1 LAST HDL_TAP TRUE
J 0
(-5250 3325);
DISPLAY 1.595745 (-5250 3325);
PAINT GREEN (-5250 3325);
DISPLAY INVISIBLE (-5250 3325);
FORCEPROP 1 LAST PATH I61
J 0
(-5577 3450);
DISPLAY 0.872340 (-5577 3450);
PAINT GREEN (-5577 3450);
DISPLAY INVISIBLE (-5577 3450);
FORCEADD TAP..6
(-5575 3500);
FORCEPROP 3 LASTPIN (-5525 3500) SIG_NAME M_E_DQ<40>
J 0
(-5515 3510);
DISPLAY 0.659574 (-5515 3510);
PAINT MONO (-5515 3510);
DISPLAY INVISIBLE (-5515 3510);
FORCEPROP 1 LASTPIN (-5525 3500) BN 40
J 0
(-5577 3508);
DISPLAY 0.617021 (-5577 3508);
PAINT PINK (-5577 3508);
FORCEPROP 2 LAST CDS_LIB mstr_standard
J 0
(-5575 3500);
PAINT MONO (-5575 3500);
DISPLAY INVISIBLE (-5575 3500);
FORCEPROP 1 LAST BODY_TYPE PLUMBING
J 0
(-5575 3450);
DISPLAY 1.595745 (-5575 3450);
PAINT GREEN (-5575 3450);
DISPLAY INVISIBLE (-5575 3450);
FORCEPROP 1 LAST HDL_TAP TRUE
J 0
(-5250 3375);
DISPLAY 1.595745 (-5250 3375);
PAINT GREEN (-5250 3375);
DISPLAY INVISIBLE (-5250 3375);
FORCEPROP 1 LAST PATH I62
J 0
(-5577 3500);
DISPLAY 0.872340 (-5577 3500);
PAINT GREEN (-5577 3500);
DISPLAY INVISIBLE (-5577 3500);
FORCEADD TAP..6
(-5575 3550);
FORCEPROP 3 LASTPIN (-5525 3550) SIG_NAME M_E_DQ<41>
J 0
(-5515 3560);
DISPLAY 0.659574 (-5515 3560);
PAINT MONO (-5515 3560);
DISPLAY INVISIBLE (-5515 3560);
FORCEPROP 1 LASTPIN (-5525 3550) BN 41
J 0
(-5577 3558);
DISPLAY 0.617021 (-5577 3558);
PAINT PINK (-5577 3558);
FORCEPROP 2 LAST CDS_LIB mstr_standard
J 0
(-5575 3550);
PAINT MONO (-5575 3550);
DISPLAY INVISIBLE (-5575 3550);
FORCEPROP 1 LAST BODY_TYPE PLUMBING
J 0
(-5575 3500);
DISPLAY 1.595745 (-5575 3500);
PAINT GREEN (-5575 3500);
DISPLAY INVISIBLE (-5575 3500);
FORCEPROP 1 LAST HDL_TAP TRUE
J 0
(-5250 3425);
DISPLAY 1.595745 (-5250 3425);
PAINT GREEN (-5250 3425);
DISPLAY INVISIBLE (-5250 3425);
FORCEPROP 1 LAST PATH I63
J 0
(-5577 3550);
DISPLAY 0.872340 (-5577 3550);
PAINT GREEN (-5577 3550);
DISPLAY INVISIBLE (-5577 3550);
FORCEADD TAP..6
(-5575 3600);
FORCEPROP 3 LASTPIN (-5525 3600) SIG_NAME M_E_DQ<42>
J 0
(-5515 3610);
DISPLAY 0.659574 (-5515 3610);
PAINT MONO (-5515 3610);
DISPLAY INVISIBLE (-5515 3610);
FORCEPROP 1 LASTPIN (-5525 3600) BN 42
J 0
(-5577 3608);
DISPLAY 0.617021 (-5577 3608);
PAINT PINK (-5577 3608);
FORCEPROP 2 LAST CDS_LIB mstr_standard
J 0
(-5575 3600);
PAINT MONO (-5575 3600);
DISPLAY INVISIBLE (-5575 3600);
FORCEPROP 1 LAST BODY_TYPE PLUMBING
J 0
(-5575 3550);
DISPLAY 1.595745 (-5575 3550);
PAINT GREEN (-5575 3550);
DISPLAY INVISIBLE (-5575 3550);
FORCEPROP 1 LAST HDL_TAP TRUE
J 0
(-5250 3475);
DISPLAY 1.595745 (-5250 3475);
PAINT GREEN (-5250 3475);
DISPLAY INVISIBLE (-5250 3475);
FORCEPROP 1 LAST PATH I64
J 0
(-5577 3600);
DISPLAY 0.872340 (-5577 3600);
PAINT GREEN (-5577 3600);
DISPLAY INVISIBLE (-5577 3600);
FORCEADD TAP..6
(-5575 3650);
FORCEPROP 3 LASTPIN (-5525 3650) SIG_NAME M_E_DQ<43>
J 0
(-5515 3660);
DISPLAY 0.659574 (-5515 3660);
PAINT MONO (-5515 3660);
DISPLAY INVISIBLE (-5515 3660);
FORCEPROP 1 LASTPIN (-5525 3650) BN 43
J 0
(-5577 3658);
DISPLAY 0.617021 (-5577 3658);
PAINT PINK (-5577 3658);
FORCEPROP 2 LAST CDS_LIB mstr_standard
J 0
(-5575 3650);
PAINT MONO (-5575 3650);
DISPLAY INVISIBLE (-5575 3650);
FORCEPROP 1 LAST BODY_TYPE PLUMBING
J 0
(-5575 3600);
DISPLAY 1.595745 (-5575 3600);
PAINT GREEN (-5575 3600);
DISPLAY INVISIBLE (-5575 3600);
FORCEPROP 1 LAST HDL_TAP TRUE
J 0
(-5250 3525);
DISPLAY 1.595745 (-5250 3525);
PAINT GREEN (-5250 3525);
DISPLAY INVISIBLE (-5250 3525);
FORCEPROP 1 LAST PATH I65
J 0
(-5577 3650);
DISPLAY 0.872340 (-5577 3650);
PAINT GREEN (-5577 3650);
DISPLAY INVISIBLE (-5577 3650);
FORCEADD TAP..6
(-5575 3700);
FORCEPROP 3 LASTPIN (-5525 3700) SIG_NAME M_E_DQ<44>
J 0
(-5515 3710);
DISPLAY 0.659574 (-5515 3710);
PAINT MONO (-5515 3710);
DISPLAY INVISIBLE (-5515 3710);
FORCEPROP 1 LASTPIN (-5525 3700) BN 44
J 0
(-5577 3708);
DISPLAY 0.617021 (-5577 3708);
PAINT PINK (-5577 3708);
FORCEPROP 2 LAST CDS_LIB mstr_standard
J 0
(-5575 3700);
PAINT MONO (-5575 3700);
DISPLAY INVISIBLE (-5575 3700);
FORCEPROP 1 LAST BODY_TYPE PLUMBING
J 0
(-5575 3650);
DISPLAY 1.595745 (-5575 3650);
PAINT GREEN (-5575 3650);
DISPLAY INVISIBLE (-5575 3650);
FORCEPROP 1 LAST HDL_TAP TRUE
J 0
(-5250 3575);
DISPLAY 1.595745 (-5250 3575);
PAINT GREEN (-5250 3575);
DISPLAY INVISIBLE (-5250 3575);
FORCEPROP 1 LAST PATH I66
J 0
(-5577 3700);
DISPLAY 0.872340 (-5577 3700);
PAINT GREEN (-5577 3700);
DISPLAY INVISIBLE (-5577 3700);
FORCEADD TAP..6
(-5575 3750);
FORCEPROP 3 LASTPIN (-5525 3750) SIG_NAME M_E_DQ<45>
J 0
(-5515 3760);
DISPLAY 0.659574 (-5515 3760);
PAINT MONO (-5515 3760);
DISPLAY INVISIBLE (-5515 3760);
FORCEPROP 1 LASTPIN (-5525 3750) BN 45
J 0
(-5577 3758);
DISPLAY 0.617021 (-5577 3758);
PAINT PINK (-5577 3758);
FORCEPROP 2 LAST CDS_LIB mstr_standard
J 0
(-5575 3750);
PAINT MONO (-5575 3750);
DISPLAY INVISIBLE (-5575 3750);
FORCEPROP 1 LAST BODY_TYPE PLUMBING
J 0
(-5575 3700);
DISPLAY 1.595745 (-5575 3700);
PAINT GREEN (-5575 3700);
DISPLAY INVISIBLE (-5575 3700);
FORCEPROP 1 LAST HDL_TAP TRUE
J 0
(-5250 3625);
DISPLAY 1.595745 (-5250 3625);
PAINT GREEN (-5250 3625);
DISPLAY INVISIBLE (-5250 3625);
FORCEPROP 1 LAST PATH I67
J 0
(-5577 3750);
DISPLAY 0.872340 (-5577 3750);
PAINT GREEN (-5577 3750);
DISPLAY INVISIBLE (-5577 3750);
FORCEADD TAP..6
(-5575 3800);
FORCEPROP 3 LASTPIN (-5525 3800) SIG_NAME M_E_DQ<46>
J 0
(-5515 3810);
DISPLAY 0.659574 (-5515 3810);
PAINT MONO (-5515 3810);
DISPLAY INVISIBLE (-5515 3810);
FORCEPROP 1 LASTPIN (-5525 3800) BN 46
J 0
(-5577 3808);
DISPLAY 0.617021 (-5577 3808);
PAINT PINK (-5577 3808);
FORCEPROP 2 LAST CDS_LIB mstr_standard
J 0
(-5575 3800);
PAINT MONO (-5575 3800);
DISPLAY INVISIBLE (-5575 3800);
FORCEPROP 1 LAST BODY_TYPE PLUMBING
J 0
(-5575 3750);
DISPLAY 1.595745 (-5575 3750);
PAINT GREEN (-5575 3750);
DISPLAY INVISIBLE (-5575 3750);
FORCEPROP 1 LAST HDL_TAP TRUE
J 0
(-5250 3675);
DISPLAY 1.595745 (-5250 3675);
PAINT GREEN (-5250 3675);
DISPLAY INVISIBLE (-5250 3675);
FORCEPROP 1 LAST PATH I68
J 0
(-5577 3800);
DISPLAY 0.872340 (-5577 3800);
PAINT GREEN (-5577 3800);
DISPLAY INVISIBLE (-5577 3800);
FORCEADD TAP..6
(-5575 3850);
FORCEPROP 3 LASTPIN (-5525 3850) SIG_NAME M_E_DQ<47>
J 0
(-5515 3860);
DISPLAY 0.659574 (-5515 3860);
PAINT MONO (-5515 3860);
DISPLAY INVISIBLE (-5515 3860);
FORCEPROP 1 LASTPIN (-5525 3850) BN 47
J 0
(-5577 3858);
DISPLAY 0.617021 (-5577 3858);
PAINT PINK (-5577 3858);
FORCEPROP 2 LAST CDS_LIB mstr_standard
J 0
(-5575 3850);
PAINT MONO (-5575 3850);
DISPLAY INVISIBLE (-5575 3850);
FORCEPROP 1 LAST BODY_TYPE PLUMBING
J 0
(-5575 3800);
DISPLAY 1.595745 (-5575 3800);
PAINT GREEN (-5575 3800);
DISPLAY INVISIBLE (-5575 3800);
FORCEPROP 1 LAST HDL_TAP TRUE
J 0
(-5250 3725);
DISPLAY 1.595745 (-5250 3725);
PAINT GREEN (-5250 3725);
DISPLAY INVISIBLE (-5250 3725);
FORCEPROP 1 LAST PATH I69
J 0
(-5577 3850);
DISPLAY 0.872340 (-5577 3850);
PAINT GREEN (-5577 3850);
DISPLAY INVISIBLE (-5577 3850);
FORCEADD TAP..6
(-5575 750);
FORCEPROP 3 LASTPIN (-5525 750) SIG_NAME M_E_CLK_DN<3>
J 0
(-5515 760);
DISPLAY 0.659574 (-5515 760);
PAINT MONO (-5515 760);
DISPLAY INVISIBLE (-5515 760);
FORCEPROP 1 LASTPIN (-5525 750) BN 3
J 0
(-5577 758);
DISPLAY 0.617021 (-5577 758);
PAINT PINK (-5577 758);
FORCEPROP 2 LAST CDS_LIB mstr_standard
J 0
(-5575 750);
PAINT MONO (-5575 750);
DISPLAY INVISIBLE (-5575 750);
FORCEPROP 1 LAST BODY_TYPE PLUMBING
J 0
(-5575 700);
DISPLAY 1.595745 (-5575 700);
PAINT GREEN (-5575 700);
DISPLAY INVISIBLE (-5575 700);
FORCEPROP 1 LAST HDL_TAP TRUE
J 0
(-5250 625);
DISPLAY 1.595745 (-5250 625);
PAINT GREEN (-5250 625);
DISPLAY INVISIBLE (-5250 625);
FORCEPROP 1 LAST PATH I7
J 0
(-5577 750);
DISPLAY 0.872340 (-5577 750);
PAINT GREEN (-5577 750);
DISPLAY INVISIBLE (-5577 750);
FORCEADD TAP..6
(-5575 3900);
FORCEPROP 3 LASTPIN (-5525 3900) SIG_NAME M_E_DQ<48>
J 0
(-5515 3910);
DISPLAY 0.659574 (-5515 3910);
PAINT MONO (-5515 3910);
DISPLAY INVISIBLE (-5515 3910);
FORCEPROP 1 LASTPIN (-5525 3900) BN 48
J 0
(-5577 3908);
DISPLAY 0.617021 (-5577 3908);
PAINT PINK (-5577 3908);
FORCEPROP 2 LAST CDS_LIB mstr_standard
J 0
(-5575 3900);
PAINT MONO (-5575 3900);
DISPLAY INVISIBLE (-5575 3900);
FORCEPROP 1 LAST BODY_TYPE PLUMBING
J 0
(-5575 3850);
DISPLAY 1.595745 (-5575 3850);
PAINT GREEN (-5575 3850);
DISPLAY INVISIBLE (-5575 3850);
FORCEPROP 1 LAST HDL_TAP TRUE
J 0
(-5250 3775);
DISPLAY 1.595745 (-5250 3775);
PAINT GREEN (-5250 3775);
DISPLAY INVISIBLE (-5250 3775);
FORCEPROP 1 LAST PATH I70
J 0
(-5577 3900);
DISPLAY 0.872340 (-5577 3900);
PAINT GREEN (-5577 3900);
DISPLAY INVISIBLE (-5577 3900);
FORCEADD TAP..6
(-5575 3950);
FORCEPROP 3 LASTPIN (-5525 3950) SIG_NAME M_E_DQ<49>
J 0
(-5515 3960);
DISPLAY 0.659574 (-5515 3960);
PAINT MONO (-5515 3960);
DISPLAY INVISIBLE (-5515 3960);
FORCEPROP 1 LASTPIN (-5525 3950) BN 49
J 0
(-5577 3958);
DISPLAY 0.617021 (-5577 3958);
PAINT PINK (-5577 3958);
FORCEPROP 2 LAST CDS_LIB mstr_standard
J 0
(-5575 3950);
PAINT MONO (-5575 3950);
DISPLAY INVISIBLE (-5575 3950);
FORCEPROP 1 LAST BODY_TYPE PLUMBING
J 0
(-5575 3900);
DISPLAY 1.595745 (-5575 3900);
PAINT GREEN (-5575 3900);
DISPLAY INVISIBLE (-5575 3900);
FORCEPROP 1 LAST HDL_TAP TRUE
J 0
(-5250 3825);
DISPLAY 1.595745 (-5250 3825);
PAINT GREEN (-5250 3825);
DISPLAY INVISIBLE (-5250 3825);
FORCEPROP 1 LAST PATH I71
J 0
(-5577 3950);
DISPLAY 0.872340 (-5577 3950);
PAINT GREEN (-5577 3950);
DISPLAY INVISIBLE (-5577 3950);
FORCEADD TAP..6
(-5575 4000);
FORCEPROP 3 LASTPIN (-5525 4000) SIG_NAME M_E_DQ<50>
J 0
(-5515 4010);
DISPLAY 0.659574 (-5515 4010);
PAINT MONO (-5515 4010);
DISPLAY INVISIBLE (-5515 4010);
FORCEPROP 1 LASTPIN (-5525 4000) BN 50
J 0
(-5577 4008);
DISPLAY 0.617021 (-5577 4008);
PAINT PINK (-5577 4008);
FORCEPROP 2 LAST CDS_LIB mstr_standard
J 0
(-5575 4000);
PAINT MONO (-5575 4000);
DISPLAY INVISIBLE (-5575 4000);
FORCEPROP 1 LAST BODY_TYPE PLUMBING
J 0
(-5575 3950);
DISPLAY 1.595745 (-5575 3950);
PAINT GREEN (-5575 3950);
DISPLAY INVISIBLE (-5575 3950);
FORCEPROP 1 LAST HDL_TAP TRUE
J 0
(-5250 3875);
DISPLAY 1.595745 (-5250 3875);
PAINT GREEN (-5250 3875);
DISPLAY INVISIBLE (-5250 3875);
FORCEPROP 1 LAST PATH I72
J 0
(-5577 4000);
DISPLAY 0.872340 (-5577 4000);
PAINT GREEN (-5577 4000);
DISPLAY INVISIBLE (-5577 4000);
FORCEADD OFFPAGE..6
(-6425 4775);
FORCEPROP 2 LAST $XR1 52 
J 0
(-6764 4775);
DISPLAY 0.638298 (-6764 4775);
PAINT MONO (-6764 4775);
FORCEPROP 2 LAST $XR0 51 
J 0
(-6674 4775);
DISPLAY 0.638298 (-6674 4775);
PAINT MONO (-6674 4775);
FORCEPROP 2 LAST CDS_LIB mstr_standard
J 0
(-6425 4775);
PAINT MONO (-6425 4775);
DISPLAY INVISIBLE (-6425 4775);
FORCEPROP 1 LAST OFFPAGE TRUE
J 0
(-6100 4650);
DISPLAY 1.170213 (-6100 4650);
PAINT GREEN (-6100 4650);
DISPLAY INVISIBLE (-6100 4650);
FORCEPROP 1 LAST COMMENT_BODY TRUE
J 0
(-6325 4700);
DISPLAY 1.170213 (-6325 4700);
PAINT GREEN (-6325 4700);
DISPLAY INVISIBLE (-6325 4700);
FORCEPROP 2 LAST PATH I73
J 0
(-6375 4850);
DISPLAY 1.021277 (-6375 4850);
PAINT ORANGE (-6375 4850);
DISPLAY INVISIBLE (-6375 4850);
FORCEADD TAP..6
(-5575 4050);
FORCEPROP 3 LASTPIN (-5525 4050) SIG_NAME M_E_DQ<51>
J 0
(-5515 4060);
DISPLAY 0.659574 (-5515 4060);
PAINT MONO (-5515 4060);
DISPLAY INVISIBLE (-5515 4060);
FORCEPROP 1 LASTPIN (-5525 4050) BN 51
J 0
(-5577 4058);
DISPLAY 0.617021 (-5577 4058);
PAINT PINK (-5577 4058);
FORCEPROP 2 LAST CDS_LIB mstr_standard
J 0
(-5575 4050);
PAINT MONO (-5575 4050);
DISPLAY INVISIBLE (-5575 4050);
FORCEPROP 1 LAST BODY_TYPE PLUMBING
J 0
(-5575 4000);
DISPLAY 1.595745 (-5575 4000);
PAINT GREEN (-5575 4000);
DISPLAY INVISIBLE (-5575 4000);
FORCEPROP 1 LAST HDL_TAP TRUE
J 0
(-5250 3925);
DISPLAY 1.595745 (-5250 3925);
PAINT GREEN (-5250 3925);
DISPLAY INVISIBLE (-5250 3925);
FORCEPROP 1 LAST PATH I74
J 0
(-5577 4050);
DISPLAY 0.872340 (-5577 4050);
PAINT GREEN (-5577 4050);
DISPLAY INVISIBLE (-5577 4050);
FORCEADD TAP..6
(-5575 4100);
FORCEPROP 3 LASTPIN (-5525 4100) SIG_NAME M_E_DQ<52>
J 0
(-5515 4110);
DISPLAY 0.659574 (-5515 4110);
PAINT MONO (-5515 4110);
DISPLAY INVISIBLE (-5515 4110);
FORCEPROP 1 LASTPIN (-5525 4100) BN 52
J 0
(-5577 4108);
DISPLAY 0.617021 (-5577 4108);
PAINT PINK (-5577 4108);
FORCEPROP 2 LAST CDS_LIB mstr_standard
J 0
(-5575 4100);
PAINT MONO (-5575 4100);
DISPLAY INVISIBLE (-5575 4100);
FORCEPROP 1 LAST BODY_TYPE PLUMBING
J 0
(-5575 4050);
DISPLAY 1.595745 (-5575 4050);
PAINT GREEN (-5575 4050);
DISPLAY INVISIBLE (-5575 4050);
FORCEPROP 1 LAST HDL_TAP TRUE
J 0
(-5250 3975);
DISPLAY 1.595745 (-5250 3975);
PAINT GREEN (-5250 3975);
DISPLAY INVISIBLE (-5250 3975);
FORCEPROP 1 LAST PATH I75
J 0
(-5577 4100);
DISPLAY 0.872340 (-5577 4100);
PAINT GREEN (-5577 4100);
DISPLAY INVISIBLE (-5577 4100);
FORCEADD TAP..6
(-5575 4150);
FORCEPROP 3 LASTPIN (-5525 4150) SIG_NAME M_E_DQ<53>
J 0
(-5515 4160);
DISPLAY 0.659574 (-5515 4160);
PAINT MONO (-5515 4160);
DISPLAY INVISIBLE (-5515 4160);
FORCEPROP 1 LASTPIN (-5525 4150) BN 53
J 0
(-5577 4158);
DISPLAY 0.617021 (-5577 4158);
PAINT PINK (-5577 4158);
FORCEPROP 2 LAST CDS_LIB mstr_standard
J 0
(-5575 4150);
PAINT MONO (-5575 4150);
DISPLAY INVISIBLE (-5575 4150);
FORCEPROP 1 LAST BODY_TYPE PLUMBING
J 0
(-5575 4100);
DISPLAY 1.595745 (-5575 4100);
PAINT GREEN (-5575 4100);
DISPLAY INVISIBLE (-5575 4100);
FORCEPROP 1 LAST HDL_TAP TRUE
J 0
(-5250 4025);
DISPLAY 1.595745 (-5250 4025);
PAINT GREEN (-5250 4025);
DISPLAY INVISIBLE (-5250 4025);
FORCEPROP 1 LAST PATH I76
J 0
(-5577 4150);
DISPLAY 0.872340 (-5577 4150);
PAINT GREEN (-5577 4150);
DISPLAY INVISIBLE (-5577 4150);
FORCEADD TAP..6
(-5575 4200);
FORCEPROP 3 LASTPIN (-5525 4200) SIG_NAME M_E_DQ<54>
J 0
(-5515 4210);
DISPLAY 0.659574 (-5515 4210);
PAINT MONO (-5515 4210);
DISPLAY INVISIBLE (-5515 4210);
FORCEPROP 1 LASTPIN (-5525 4200) BN 54
J 0
(-5577 4208);
DISPLAY 0.617021 (-5577 4208);
PAINT PINK (-5577 4208);
FORCEPROP 2 LAST CDS_LIB mstr_standard
J 0
(-5575 4200);
PAINT MONO (-5575 4200);
DISPLAY INVISIBLE (-5575 4200);
FORCEPROP 1 LAST BODY_TYPE PLUMBING
J 0
(-5575 4150);
DISPLAY 1.595745 (-5575 4150);
PAINT GREEN (-5575 4150);
DISPLAY INVISIBLE (-5575 4150);
FORCEPROP 1 LAST HDL_TAP TRUE
J 0
(-5250 4075);
DISPLAY 1.595745 (-5250 4075);
PAINT GREEN (-5250 4075);
DISPLAY INVISIBLE (-5250 4075);
FORCEPROP 1 LAST PATH I77
J 0
(-5577 4200);
DISPLAY 0.872340 (-5577 4200);
PAINT GREEN (-5577 4200);
DISPLAY INVISIBLE (-5577 4200);
FORCEADD TAP..6
(-5575 4250);
FORCEPROP 3 LASTPIN (-5525 4250) SIG_NAME M_E_DQ<55>
J 0
(-5515 4260);
DISPLAY 0.659574 (-5515 4260);
PAINT MONO (-5515 4260);
DISPLAY INVISIBLE (-5515 4260);
FORCEPROP 1 LASTPIN (-5525 4250) BN 55
J 0
(-5577 4258);
DISPLAY 0.617021 (-5577 4258);
PAINT PINK (-5577 4258);
FORCEPROP 2 LAST CDS_LIB mstr_standard
J 0
(-5575 4250);
PAINT MONO (-5575 4250);
DISPLAY INVISIBLE (-5575 4250);
FORCEPROP 1 LAST BODY_TYPE PLUMBING
J 0
(-5575 4200);
DISPLAY 1.595745 (-5575 4200);
PAINT GREEN (-5575 4200);
DISPLAY INVISIBLE (-5575 4200);
FORCEPROP 1 LAST HDL_TAP TRUE
J 0
(-5250 4125);
DISPLAY 1.595745 (-5250 4125);
PAINT GREEN (-5250 4125);
DISPLAY INVISIBLE (-5250 4125);
FORCEPROP 1 LAST PATH I78
J 0
(-5577 4250);
DISPLAY 0.872340 (-5577 4250);
PAINT GREEN (-5577 4250);
DISPLAY INVISIBLE (-5577 4250);
FORCEADD TAP..6
(-5575 4300);
FORCEPROP 3 LASTPIN (-5525 4300) SIG_NAME M_E_DQ<56>
J 0
(-5515 4310);
DISPLAY 0.659574 (-5515 4310);
PAINT MONO (-5515 4310);
DISPLAY INVISIBLE (-5515 4310);
FORCEPROP 1 LASTPIN (-5525 4300) BN 56
J 0
(-5577 4308);
DISPLAY 0.617021 (-5577 4308);
PAINT PINK (-5577 4308);
FORCEPROP 2 LAST CDS_LIB mstr_standard
J 0
(-5575 4300);
PAINT MONO (-5575 4300);
DISPLAY INVISIBLE (-5575 4300);
FORCEPROP 1 LAST BODY_TYPE PLUMBING
J 0
(-5575 4250);
DISPLAY 1.595745 (-5575 4250);
PAINT GREEN (-5575 4250);
DISPLAY INVISIBLE (-5575 4250);
FORCEPROP 1 LAST HDL_TAP TRUE
J 0
(-5250 4175);
DISPLAY 1.595745 (-5250 4175);
PAINT GREEN (-5250 4175);
DISPLAY INVISIBLE (-5250 4175);
FORCEPROP 1 LAST PATH I79
J 0
(-5577 4300);
DISPLAY 0.872340 (-5577 4300);
PAINT GREEN (-5577 4300);
DISPLAY INVISIBLE (-5577 4300);
FORCEADD TAP..6
(-5575 700);
FORCEPROP 3 LASTPIN (-5525 700) SIG_NAME M_E_CLK_DN<2>
J 0
(-5515 710);
DISPLAY 0.659574 (-5515 710);
PAINT MONO (-5515 710);
DISPLAY INVISIBLE (-5515 710);
FORCEPROP 1 LASTPIN (-5525 700) BN 2
J 0
(-5577 708);
DISPLAY 0.617021 (-5577 708);
PAINT PINK (-5577 708);
FORCEPROP 2 LAST CDS_LIB mstr_standard
J 0
(-5575 700);
PAINT MONO (-5575 700);
DISPLAY INVISIBLE (-5575 700);
FORCEPROP 1 LAST BODY_TYPE PLUMBING
J 0
(-5575 650);
DISPLAY 1.595745 (-5575 650);
PAINT GREEN (-5575 650);
DISPLAY INVISIBLE (-5575 650);
FORCEPROP 1 LAST HDL_TAP TRUE
J 0
(-5250 575);
DISPLAY 1.595745 (-5250 575);
PAINT GREEN (-5250 575);
DISPLAY INVISIBLE (-5250 575);
FORCEPROP 1 LAST PATH I8
J 0
(-5577 700);
DISPLAY 0.872340 (-5577 700);
PAINT GREEN (-5577 700);
DISPLAY INVISIBLE (-5577 700);
FORCEADD TAP..6
(-5575 4350);
FORCEPROP 3 LASTPIN (-5525 4350) SIG_NAME M_E_DQ<57>
J 0
(-5515 4360);
DISPLAY 0.659574 (-5515 4360);
PAINT MONO (-5515 4360);
DISPLAY INVISIBLE (-5515 4360);
FORCEPROP 1 LASTPIN (-5525 4350) BN 57
J 0
(-5577 4358);
DISPLAY 0.617021 (-5577 4358);
PAINT PINK (-5577 4358);
FORCEPROP 2 LAST CDS_LIB mstr_standard
J 0
(-5575 4350);
PAINT MONO (-5575 4350);
DISPLAY INVISIBLE (-5575 4350);
FORCEPROP 1 LAST BODY_TYPE PLUMBING
J 0
(-5575 4300);
DISPLAY 1.595745 (-5575 4300);
PAINT GREEN (-5575 4300);
DISPLAY INVISIBLE (-5575 4300);
FORCEPROP 1 LAST HDL_TAP TRUE
J 0
(-5250 4225);
DISPLAY 1.595745 (-5250 4225);
PAINT GREEN (-5250 4225);
DISPLAY INVISIBLE (-5250 4225);
FORCEPROP 1 LAST PATH I80
J 0
(-5577 4350);
DISPLAY 0.872340 (-5577 4350);
PAINT GREEN (-5577 4350);
DISPLAY INVISIBLE (-5577 4350);
FORCEADD TAP..6
(-5575 4400);
FORCEPROP 3 LASTPIN (-5525 4400) SIG_NAME M_E_DQ<58>
J 0
(-5515 4410);
DISPLAY 0.659574 (-5515 4410);
PAINT MONO (-5515 4410);
DISPLAY INVISIBLE (-5515 4410);
FORCEPROP 1 LASTPIN (-5525 4400) BN 58
J 0
(-5577 4408);
DISPLAY 0.617021 (-5577 4408);
PAINT PINK (-5577 4408);
FORCEPROP 2 LAST CDS_LIB mstr_standard
J 0
(-5575 4400);
PAINT MONO (-5575 4400);
DISPLAY INVISIBLE (-5575 4400);
FORCEPROP 1 LAST BODY_TYPE PLUMBING
J 0
(-5575 4350);
DISPLAY 1.595745 (-5575 4350);
PAINT GREEN (-5575 4350);
DISPLAY INVISIBLE (-5575 4350);
FORCEPROP 1 LAST HDL_TAP TRUE
J 0
(-5250 4275);
DISPLAY 1.595745 (-5250 4275);
PAINT GREEN (-5250 4275);
DISPLAY INVISIBLE (-5250 4275);
FORCEPROP 1 LAST PATH I81
J 0
(-5577 4400);
DISPLAY 0.872340 (-5577 4400);
PAINT GREEN (-5577 4400);
DISPLAY INVISIBLE (-5577 4400);
FORCEADD TAP..6
(-5575 4450);
FORCEPROP 3 LASTPIN (-5525 4450) SIG_NAME M_E_DQ<59>
J 0
(-5515 4460);
DISPLAY 0.659574 (-5515 4460);
PAINT MONO (-5515 4460);
DISPLAY INVISIBLE (-5515 4460);
FORCEPROP 1 LASTPIN (-5525 4450) BN 59
J 0
(-5577 4458);
DISPLAY 0.617021 (-5577 4458);
PAINT PINK (-5577 4458);
FORCEPROP 2 LAST CDS_LIB mstr_standard
J 0
(-5575 4450);
PAINT MONO (-5575 4450);
DISPLAY INVISIBLE (-5575 4450);
FORCEPROP 1 LAST BODY_TYPE PLUMBING
J 0
(-5575 4400);
DISPLAY 1.595745 (-5575 4400);
PAINT GREEN (-5575 4400);
DISPLAY INVISIBLE (-5575 4400);
FORCEPROP 1 LAST HDL_TAP TRUE
J 0
(-5250 4325);
DISPLAY 1.595745 (-5250 4325);
PAINT GREEN (-5250 4325);
DISPLAY INVISIBLE (-5250 4325);
FORCEPROP 1 LAST PATH I82
J 0
(-5577 4450);
DISPLAY 0.872340 (-5577 4450);
PAINT GREEN (-5577 4450);
DISPLAY INVISIBLE (-5577 4450);
FORCEADD TAP..6
(-5575 4500);
FORCEPROP 3 LASTPIN (-5525 4500) SIG_NAME M_E_DQ<60>
J 0
(-5515 4510);
DISPLAY 0.659574 (-5515 4510);
PAINT MONO (-5515 4510);
DISPLAY INVISIBLE (-5515 4510);
FORCEPROP 1 LASTPIN (-5525 4500) BN 60
J 0
(-5577 4508);
DISPLAY 0.617021 (-5577 4508);
PAINT PINK (-5577 4508);
FORCEPROP 2 LAST CDS_LIB mstr_standard
J 0
(-5575 4500);
PAINT MONO (-5575 4500);
DISPLAY INVISIBLE (-5575 4500);
FORCEPROP 1 LAST BODY_TYPE PLUMBING
J 0
(-5575 4450);
DISPLAY 1.595745 (-5575 4450);
PAINT GREEN (-5575 4450);
DISPLAY INVISIBLE (-5575 4450);
FORCEPROP 1 LAST HDL_TAP TRUE
J 0
(-5250 4375);
DISPLAY 1.595745 (-5250 4375);
PAINT GREEN (-5250 4375);
DISPLAY INVISIBLE (-5250 4375);
FORCEPROP 1 LAST PATH I83
J 0
(-5577 4500);
DISPLAY 0.872340 (-5577 4500);
PAINT GREEN (-5577 4500);
DISPLAY INVISIBLE (-5577 4500);
FORCEADD TAP..6
(-5575 4550);
FORCEPROP 3 LASTPIN (-5525 4550) SIG_NAME M_E_DQ<61>
J 0
(-5515 4560);
DISPLAY 0.659574 (-5515 4560);
PAINT MONO (-5515 4560);
DISPLAY INVISIBLE (-5515 4560);
FORCEPROP 1 LASTPIN (-5525 4550) BN 61
J 0
(-5577 4558);
DISPLAY 0.617021 (-5577 4558);
PAINT PINK (-5577 4558);
FORCEPROP 2 LAST CDS_LIB mstr_standard
J 0
(-5575 4550);
PAINT MONO (-5575 4550);
DISPLAY INVISIBLE (-5575 4550);
FORCEPROP 1 LAST BODY_TYPE PLUMBING
J 0
(-5575 4500);
DISPLAY 1.595745 (-5575 4500);
PAINT GREEN (-5575 4500);
DISPLAY INVISIBLE (-5575 4500);
FORCEPROP 1 LAST HDL_TAP TRUE
J 0
(-5250 4425);
DISPLAY 1.595745 (-5250 4425);
PAINT GREEN (-5250 4425);
DISPLAY INVISIBLE (-5250 4425);
FORCEPROP 1 LAST PATH I84
J 0
(-5577 4550);
DISPLAY 0.872340 (-5577 4550);
PAINT GREEN (-5577 4550);
DISPLAY INVISIBLE (-5577 4550);
FORCEADD TAP..6
(-5575 4600);
FORCEPROP 3 LASTPIN (-5525 4600) SIG_NAME M_E_DQ<62>
J 0
(-5515 4610);
DISPLAY 0.659574 (-5515 4610);
PAINT MONO (-5515 4610);
DISPLAY INVISIBLE (-5515 4610);
FORCEPROP 1 LASTPIN (-5525 4600) BN 62
J 0
(-5577 4608);
DISPLAY 0.617021 (-5577 4608);
PAINT PINK (-5577 4608);
FORCEPROP 2 LAST CDS_LIB mstr_standard
J 0
(-5575 4600);
PAINT MONO (-5575 4600);
DISPLAY INVISIBLE (-5575 4600);
FORCEPROP 1 LAST BODY_TYPE PLUMBING
J 0
(-5575 4550);
DISPLAY 1.595745 (-5575 4550);
PAINT GREEN (-5575 4550);
DISPLAY INVISIBLE (-5575 4550);
FORCEPROP 1 LAST HDL_TAP TRUE
J 0
(-5250 4475);
DISPLAY 1.595745 (-5250 4475);
PAINT GREEN (-5250 4475);
DISPLAY INVISIBLE (-5250 4475);
FORCEPROP 1 LAST PATH I85
J 0
(-5577 4600);
DISPLAY 0.872340 (-5577 4600);
PAINT GREEN (-5577 4600);
DISPLAY INVISIBLE (-5577 4600);
FORCEADD TAP..6
(-5575 4650);
FORCEPROP 3 LASTPIN (-5525 4650) SIG_NAME M_E_DQ<63>
J 0
(-5515 4660);
DISPLAY 0.659574 (-5515 4660);
PAINT MONO (-5515 4660);
DISPLAY INVISIBLE (-5515 4660);
FORCEPROP 1 LASTPIN (-5525 4650) BN 63
J 0
(-5577 4658);
DISPLAY 0.617021 (-5577 4658);
PAINT PINK (-5577 4658);
FORCEPROP 2 LAST CDS_LIB mstr_standard
J 0
(-5575 4650);
PAINT MONO (-5575 4650);
DISPLAY INVISIBLE (-5575 4650);
FORCEPROP 1 LAST BODY_TYPE PLUMBING
J 0
(-5575 4600);
DISPLAY 1.595745 (-5575 4600);
PAINT GREEN (-5575 4600);
DISPLAY INVISIBLE (-5575 4600);
FORCEPROP 1 LAST HDL_TAP TRUE
J 0
(-5250 4525);
DISPLAY 1.595745 (-5250 4525);
PAINT GREEN (-5250 4525);
DISPLAY INVISIBLE (-5250 4525);
FORCEPROP 1 LAST PATH I86
J 0
(-5577 4650);
DISPLAY 0.872340 (-5577 4650);
PAINT GREEN (-5577 4650);
DISPLAY INVISIBLE (-5577 4650);
FORCEADD TAP..6
R 2
(-2850 800);
FORCEPROP 3 LASTPIN (-2900 800) SIG_NAME M_E_BG<0>
J 0
(-2890 810);
DISPLAY 0.659574 (-2890 810);
PAINT MONO (-2890 810);
DISPLAY INVISIBLE (-2890 810);
FORCEPROP 1 LASTPIN (-2900 800) BN 0
J 2
(-2848 808);
DISPLAY 0.617021 (-2848 808);
PAINT PINK (-2848 808);
FORCEPROP 2 LAST CDS_LIB mstr_standard
J 0
(-2850 800);
PAINT MONO (-2850 800);
DISPLAY INVISIBLE (-2850 800);
FORCEPROP 1 LAST BODY_TYPE PLUMBING
J 2
(-2850 750);
DISPLAY 1.595745 (-2850 750);
PAINT GREEN (-2850 750);
DISPLAY INVISIBLE (-2850 750);
FORCEPROP 1 LAST HDL_TAP TRUE
J 2
(-3175 675);
DISPLAY 1.595745 (-3175 675);
PAINT GREEN (-3175 675);
DISPLAY INVISIBLE (-3175 675);
FORCEPROP 1 LAST PATH I87
J 2
(-2848 800);
DISPLAY 0.872340 (-2848 800);
PAINT GREEN (-2848 800);
DISPLAY INVISIBLE (-2848 800);
FORCEADD TAP..6
R 2
(-2850 750);
FORCEPROP 3 LASTPIN (-2900 750) SIG_NAME M_E_BA<1>
J 0
(-2890 760);
DISPLAY 0.659574 (-2890 760);
PAINT MONO (-2890 760);
DISPLAY INVISIBLE (-2890 760);
FORCEPROP 1 LASTPIN (-2900 750) BN 1
J 2
(-2848 758);
DISPLAY 0.617021 (-2848 758);
PAINT PINK (-2848 758);
FORCEPROP 2 LAST CDS_LIB mstr_standard
J 0
(-2850 750);
PAINT MONO (-2850 750);
DISPLAY INVISIBLE (-2850 750);
FORCEPROP 1 LAST BODY_TYPE PLUMBING
J 2
(-2850 700);
DISPLAY 1.595745 (-2850 700);
PAINT GREEN (-2850 700);
DISPLAY INVISIBLE (-2850 700);
FORCEPROP 1 LAST HDL_TAP TRUE
J 2
(-3175 625);
DISPLAY 1.595745 (-3175 625);
PAINT GREEN (-3175 625);
DISPLAY INVISIBLE (-3175 625);
FORCEPROP 1 LAST PATH I88
J 2
(-2848 750);
DISPLAY 0.872340 (-2848 750);
PAINT GREEN (-2848 750);
DISPLAY INVISIBLE (-2848 750);
FORCEADD TAP..6
R 2
(-2850 700);
FORCEPROP 3 LASTPIN (-2900 700) SIG_NAME M_E_BA<0>
J 0
(-2890 710);
DISPLAY 0.659574 (-2890 710);
PAINT MONO (-2890 710);
DISPLAY INVISIBLE (-2890 710);
FORCEPROP 1 LASTPIN (-2900 700) BN 0
J 2
(-2848 708);
DISPLAY 0.617021 (-2848 708);
PAINT PINK (-2848 708);
FORCEPROP 2 LAST CDS_LIB mstr_standard
J 0
(-2850 700);
PAINT MONO (-2850 700);
DISPLAY INVISIBLE (-2850 700);
FORCEPROP 1 LAST BODY_TYPE PLUMBING
J 2
(-2850 650);
DISPLAY 1.595745 (-2850 650);
PAINT GREEN (-2850 650);
DISPLAY INVISIBLE (-2850 650);
FORCEPROP 1 LAST HDL_TAP TRUE
J 2
(-3175 575);
DISPLAY 1.595745 (-3175 575);
PAINT GREEN (-3175 575);
DISPLAY INVISIBLE (-3175 575);
FORCEPROP 1 LAST PATH I89
J 2
(-2848 700);
DISPLAY 0.872340 (-2848 700);
PAINT GREEN (-2848 700);
DISPLAY INVISIBLE (-2848 700);
FORCEADD TAP..6
(-5575 800);
FORCEPROP 3 LASTPIN (-5525 800) SIG_NAME M_E_CLK_DP<0>
J 0
(-5515 810);
DISPLAY 0.659574 (-5515 810);
PAINT MONO (-5515 810);
DISPLAY INVISIBLE (-5515 810);
FORCEPROP 1 LASTPIN (-5525 800) BN 0
J 0
(-5577 808);
DISPLAY 0.617021 (-5577 808);
PAINT PINK (-5577 808);
FORCEPROP 2 LAST CDS_LIB mstr_standard
J 0
(-5575 800);
PAINT MONO (-5575 800);
DISPLAY INVISIBLE (-5575 800);
FORCEPROP 1 LAST BODY_TYPE PLUMBING
J 0
(-5575 750);
DISPLAY 1.595745 (-5575 750);
PAINT GREEN (-5575 750);
DISPLAY INVISIBLE (-5575 750);
FORCEPROP 1 LAST HDL_TAP TRUE
J 0
(-5250 675);
DISPLAY 1.595745 (-5250 675);
PAINT GREEN (-5250 675);
DISPLAY INVISIBLE (-5250 675);
FORCEPROP 1 LAST PATH I9
J 0
(-5577 800);
DISPLAY 0.872340 (-5577 800);
PAINT GREEN (-5577 800);
DISPLAY INVISIBLE (-5577 800);
FORCEADD TAP..6
R 2
(-2850 850);
FORCEPROP 3 LASTPIN (-2900 850) SIG_NAME M_E_BG<1>
J 0
(-2890 860);
DISPLAY 0.659574 (-2890 860);
PAINT MONO (-2890 860);
DISPLAY INVISIBLE (-2890 860);
FORCEPROP 1 LASTPIN (-2900 850) BN 1
J 2
(-2848 858);
DISPLAY 0.617021 (-2848 858);
PAINT PINK (-2848 858);
FORCEPROP 2 LAST CDS_LIB mstr_standard
J 0
(-2850 850);
PAINT MONO (-2850 850);
DISPLAY INVISIBLE (-2850 850);
FORCEPROP 1 LAST BODY_TYPE PLUMBING
J 2
(-2850 800);
DISPLAY 1.595745 (-2850 800);
PAINT GREEN (-2850 800);
DISPLAY INVISIBLE (-2850 800);
FORCEPROP 1 LAST HDL_TAP TRUE
J 2
(-3175 725);
DISPLAY 1.595745 (-3175 725);
PAINT GREEN (-3175 725);
DISPLAY INVISIBLE (-3175 725);
FORCEPROP 1 LAST PATH I90
J 2
(-2848 850);
DISPLAY 0.872340 (-2848 850);
PAINT GREEN (-2848 850);
DISPLAY INVISIBLE (-2848 850);
FORCEADD TAP..6
R 2
(-2850 1000);
FORCEPROP 3 LASTPIN (-2900 1000) SIG_NAME M_E_CS_N<1>
J 0
(-2890 1010);
DISPLAY 0.659574 (-2890 1010);
PAINT MONO (-2890 1010);
DISPLAY INVISIBLE (-2890 1010);
FORCEPROP 1 LASTPIN (-2900 1000) BN 1
J 2
(-2848 1008);
DISPLAY 0.617021 (-2848 1008);
PAINT PINK (-2848 1008);
FORCEPROP 2 LAST CDS_LIB mstr_standard
J 0
(-2850 1000);
PAINT MONO (-2850 1000);
DISPLAY INVISIBLE (-2850 1000);
FORCEPROP 1 LAST BODY_TYPE PLUMBING
J 2
(-2850 950);
DISPLAY 1.595745 (-2850 950);
PAINT GREEN (-2850 950);
DISPLAY INVISIBLE (-2850 950);
FORCEPROP 1 LAST HDL_TAP TRUE
J 2
(-3175 875);
DISPLAY 1.595745 (-3175 875);
PAINT GREEN (-3175 875);
DISPLAY INVISIBLE (-3175 875);
FORCEPROP 1 LAST PATH I91
J 2
(-2848 1000);
DISPLAY 0.872340 (-2848 1000);
PAINT GREEN (-2848 1000);
DISPLAY INVISIBLE (-2848 1000);
FORCEADD TAP..6
R 2
(-2850 950);
FORCEPROP 3 LASTPIN (-2900 950) SIG_NAME M_E_CS_N<0>
J 0
(-2890 960);
DISPLAY 0.659574 (-2890 960);
PAINT MONO (-2890 960);
DISPLAY INVISIBLE (-2890 960);
FORCEPROP 1 LASTPIN (-2900 950) BN 0
J 2
(-2848 958);
DISPLAY 0.617021 (-2848 958);
PAINT PINK (-2848 958);
FORCEPROP 2 LAST CDS_LIB mstr_standard
J 0
(-2850 950);
PAINT MONO (-2850 950);
DISPLAY INVISIBLE (-2850 950);
FORCEPROP 1 LAST BODY_TYPE PLUMBING
J 2
(-2850 900);
DISPLAY 1.595745 (-2850 900);
PAINT GREEN (-2850 900);
DISPLAY INVISIBLE (-2850 900);
FORCEPROP 1 LAST HDL_TAP TRUE
J 2
(-3175 825);
DISPLAY 1.595745 (-3175 825);
PAINT GREEN (-3175 825);
DISPLAY INVISIBLE (-3175 825);
FORCEPROP 1 LAST PATH I92
J 2
(-2848 950);
DISPLAY 0.872340 (-2848 950);
PAINT GREEN (-2848 950);
DISPLAY INVISIBLE (-2848 950);
FORCEADD TAP..6
R 2
(-2850 1050);
FORCEPROP 3 LASTPIN (-2900 1050) SIG_NAME M_E_CS_N<2>
J 0
(-2890 1060);
DISPLAY 0.659574 (-2890 1060);
PAINT MONO (-2890 1060);
DISPLAY INVISIBLE (-2890 1060);
FORCEPROP 1 LASTPIN (-2900 1050) BN 2
J 2
(-2848 1058);
DISPLAY 0.617021 (-2848 1058);
PAINT PINK (-2848 1058);
FORCEPROP 2 LAST CDS_LIB mstr_standard
J 0
(-2850 1050);
PAINT MONO (-2850 1050);
DISPLAY INVISIBLE (-2850 1050);
FORCEPROP 1 LAST BODY_TYPE PLUMBING
J 2
(-2850 1000);
DISPLAY 1.595745 (-2850 1000);
PAINT GREEN (-2850 1000);
DISPLAY INVISIBLE (-2850 1000);
FORCEPROP 1 LAST HDL_TAP TRUE
J 2
(-3175 925);
DISPLAY 1.595745 (-3175 925);
PAINT GREEN (-3175 925);
DISPLAY INVISIBLE (-3175 925);
FORCEPROP 1 LAST PATH I93
J 2
(-2848 1050);
DISPLAY 0.872340 (-2848 1050);
PAINT GREEN (-2848 1050);
DISPLAY INVISIBLE (-2848 1050);
FORCEADD TAP..6
R 2
(-2850 1200);
FORCEPROP 3 LASTPIN (-2900 1200) SIG_NAME M_E_CS_N<5>
J 0
(-2890 1210);
DISPLAY 0.659574 (-2890 1210);
PAINT MONO (-2890 1210);
DISPLAY INVISIBLE (-2890 1210);
FORCEPROP 1 LASTPIN (-2900 1200) BN 5
J 2
(-2848 1208);
DISPLAY 0.617021 (-2848 1208);
PAINT PINK (-2848 1208);
FORCEPROP 2 LAST CDS_LIB mstr_standard
J 0
(-2850 1200);
PAINT MONO (-2850 1200);
DISPLAY INVISIBLE (-2850 1200);
FORCEPROP 1 LAST BODY_TYPE PLUMBING
J 2
(-2850 1150);
DISPLAY 1.595745 (-2850 1150);
PAINT GREEN (-2850 1150);
DISPLAY INVISIBLE (-2850 1150);
FORCEPROP 1 LAST HDL_TAP TRUE
J 2
(-3175 1075);
DISPLAY 1.595745 (-3175 1075);
PAINT GREEN (-3175 1075);
DISPLAY INVISIBLE (-3175 1075);
FORCEPROP 1 LAST PATH I94
J 2
(-2848 1200);
DISPLAY 0.872340 (-2848 1200);
PAINT GREEN (-2848 1200);
DISPLAY INVISIBLE (-2848 1200);
FORCEADD TAP..6
R 2
(-2850 1100);
FORCEPROP 3 LASTPIN (-2900 1100) SIG_NAME M_E_CS_N<3>
J 0
(-2890 1110);
DISPLAY 0.659574 (-2890 1110);
PAINT MONO (-2890 1110);
DISPLAY INVISIBLE (-2890 1110);
FORCEPROP 1 LASTPIN (-2900 1100) BN 3
J 2
(-2848 1108);
DISPLAY 0.617021 (-2848 1108);
PAINT PINK (-2848 1108);
FORCEPROP 2 LAST CDS_LIB mstr_standard
J 0
(-2850 1100);
PAINT MONO (-2850 1100);
DISPLAY INVISIBLE (-2850 1100);
FORCEPROP 1 LAST BODY_TYPE PLUMBING
J 2
(-2850 1050);
DISPLAY 1.595745 (-2850 1050);
PAINT GREEN (-2850 1050);
DISPLAY INVISIBLE (-2850 1050);
FORCEPROP 1 LAST HDL_TAP TRUE
J 2
(-3175 975);
DISPLAY 1.595745 (-3175 975);
PAINT GREEN (-3175 975);
DISPLAY INVISIBLE (-3175 975);
FORCEPROP 1 LAST PATH I95
J 2
(-2848 1100);
DISPLAY 0.872340 (-2848 1100);
PAINT GREEN (-2848 1100);
DISPLAY INVISIBLE (-2848 1100);
FORCEADD TAP..6
R 2
(-2850 1150);
FORCEPROP 3 LASTPIN (-2900 1150) SIG_NAME M_E_CS_N<4>
J 0
(-2890 1160);
DISPLAY 0.659574 (-2890 1160);
PAINT MONO (-2890 1160);
DISPLAY INVISIBLE (-2890 1160);
FORCEPROP 1 LASTPIN (-2900 1150) BN 4
J 2
(-2848 1158);
DISPLAY 0.617021 (-2848 1158);
PAINT PINK (-2848 1158);
FORCEPROP 2 LAST CDS_LIB mstr_standard
J 0
(-2850 1150);
PAINT MONO (-2850 1150);
DISPLAY INVISIBLE (-2850 1150);
FORCEPROP 1 LAST BODY_TYPE PLUMBING
J 2
(-2850 1100);
DISPLAY 1.595745 (-2850 1100);
PAINT GREEN (-2850 1100);
DISPLAY INVISIBLE (-2850 1100);
FORCEPROP 1 LAST HDL_TAP TRUE
J 2
(-3175 1025);
DISPLAY 1.595745 (-3175 1025);
PAINT GREEN (-3175 1025);
DISPLAY INVISIBLE (-3175 1025);
FORCEPROP 1 LAST PATH I96
J 2
(-2848 1150);
DISPLAY 0.872340 (-2848 1150);
PAINT GREEN (-2848 1150);
DISPLAY INVISIBLE (-2848 1150);
FORCEADD TAP..6
R 2
(-2850 1250);
FORCEPROP 3 LASTPIN (-2900 1250) SIG_NAME M_E_CS_N<6>
J 0
(-2890 1260);
DISPLAY 0.659574 (-2890 1260);
PAINT MONO (-2890 1260);
DISPLAY INVISIBLE (-2890 1260);
FORCEPROP 1 LASTPIN (-2900 1250) BN 6
J 2
(-2848 1258);
DISPLAY 0.617021 (-2848 1258);
PAINT PINK (-2848 1258);
FORCEPROP 2 LAST CDS_LIB mstr_standard
J 0
(-2850 1250);
PAINT MONO (-2850 1250);
DISPLAY INVISIBLE (-2850 1250);
FORCEPROP 1 LAST BODY_TYPE PLUMBING
J 2
(-2850 1200);
DISPLAY 1.595745 (-2850 1200);
PAINT GREEN (-2850 1200);
DISPLAY INVISIBLE (-2850 1200);
FORCEPROP 1 LAST HDL_TAP TRUE
J 2
(-3175 1125);
DISPLAY 1.595745 (-3175 1125);
PAINT GREEN (-3175 1125);
DISPLAY INVISIBLE (-3175 1125);
FORCEPROP 1 LAST PATH I97
J 2
(-2848 1250);
DISPLAY 0.872340 (-2848 1250);
PAINT GREEN (-2848 1250);
DISPLAY INVISIBLE (-2848 1250);
FORCEADD TAP..6
R 2
(-2850 1300);
FORCEPROP 3 LASTPIN (-2900 1300) SIG_NAME M_E_CS_N<7>
J 0
(-2890 1310);
DISPLAY 0.659574 (-2890 1310);
PAINT MONO (-2890 1310);
DISPLAY INVISIBLE (-2890 1310);
FORCEPROP 1 LASTPIN (-2900 1300) BN 7
J 2
(-2848 1308);
DISPLAY 0.617021 (-2848 1308);
PAINT PINK (-2848 1308);
FORCEPROP 2 LAST CDS_LIB mstr_standard
J 0
(-2850 1300);
PAINT MONO (-2850 1300);
DISPLAY INVISIBLE (-2850 1300);
FORCEPROP 1 LAST BODY_TYPE PLUMBING
J 2
(-2850 1250);
DISPLAY 1.595745 (-2850 1250);
PAINT GREEN (-2850 1250);
DISPLAY INVISIBLE (-2850 1250);
FORCEPROP 1 LAST HDL_TAP TRUE
J 2
(-3175 1175);
DISPLAY 1.595745 (-3175 1175);
PAINT GREEN (-3175 1175);
DISPLAY INVISIBLE (-3175 1175);
FORCEPROP 1 LAST PATH I98
J 2
(-2848 1300);
DISPLAY 0.872340 (-2848 1300);
PAINT GREEN (-2848 1300);
DISPLAY INVISIBLE (-2848 1300);
FORCEADD TAP..6
R 2
(-2850 1450);
FORCEPROP 3 LASTPIN (-2900 1450) SIG_NAME M_E_ODT<1>
J 0
(-2890 1460);
DISPLAY 0.659574 (-2890 1460);
PAINT MONO (-2890 1460);
DISPLAY INVISIBLE (-2890 1460);
FORCEPROP 1 LASTPIN (-2900 1450) BN 1
J 2
(-2848 1458);
DISPLAY 0.617021 (-2848 1458);
PAINT PINK (-2848 1458);
FORCEPROP 2 LAST CDS_LIB mstr_standard
J 0
(-2850 1450);
PAINT MONO (-2850 1450);
DISPLAY INVISIBLE (-2850 1450);
FORCEPROP 1 LAST BODY_TYPE PLUMBING
J 2
(-2850 1400);
DISPLAY 1.595745 (-2850 1400);
PAINT GREEN (-2850 1400);
DISPLAY INVISIBLE (-2850 1400);
FORCEPROP 1 LAST HDL_TAP TRUE
J 2
(-3175 1325);
DISPLAY 1.595745 (-3175 1325);
PAINT GREEN (-3175 1325);
DISPLAY INVISIBLE (-3175 1325);
FORCEPROP 1 LAST PATH I99
J 2
(-2848 1450);
DISPLAY 0.872340 (-2848 1450);
PAINT GREEN (-2848 1450);
DISPLAY INVISIBLE (-2848 1450);
FORCEADD PRELIM..10
(-4215 2540);
PAINT GRAY (-4215 2540);
FORCEPROP 2 LAST CDS_LIB mstr_misc
J 0
(-4215 2540);
PAINT ORANGE (-4215 2540);
DISPLAY INVISIBLE (-4215 2540);
FORCEPROP 1 LAST COMMENT_BODY TRUE
J 0
(-4215 2540);
PAINT ORANGE (-4215 2540);
DISPLAY INVISIBLE (-4215 2540);
FORCEADD DESIGN_NOTE..1
(-6500 300);
FORCEPROP 0 LAST L1 CPU SYMBOLS 1-30 ARE PRELIMINARY AND SUBJECT TO CHANGE
J 0
(-6700 175);
DISPLAY 1.021277 (-6700 175);
PAINT ORANGE (-6700 175);
FORCEPROP 2 LAST CDS_LIB mstr_symbols
J 0
(-6500 300);
PAINT ORANGE (-6500 300);
DISPLAY INVISIBLE (-6500 300);
FORCEPROP 1 LAST COMMENT_BODY TRUE
J 0
(-6475 400);
DISPLAY 0.978723 (-6475 400);
PAINT ORANGE (-6475 400);
DISPLAY INVISIBLE (-6475 400);
FORCEADD INTEL_CORP_BPAGE..1
(0 0);
FORCEPROP 1 LAST CDS_CON_LAST_MODIFIED Fri Jun 16 17:48:11 2017
J 0
(-1425 325);
DISPLAY 1.340426 (-1425 325);
PAINT GREEN (-1425 325);
DISPLAY INVISIBLE (-1425 325);
FORCEPROP 1 LAST CUSTOM_TXT_CDS <CURRENT_DESIGN_SHEET> OF <TOTAL_DESIGN_SHEETS>
J 0
(-500 25);
PAINT ORANGE (-500 25);
FORCEPROP 1 LAST CUSTOM_TXT_CDS <CON_LAST_MODIFIED>
J 0
(-4000 100);
PAINT ORANGE (-4000 100);
FORCEPROP 2 LAST CUSTOM_TXT_CDS <XR_PAGE_TITLE>
J 0
(-7890 5250);
DISPLAY 0.638298 (-7890 5250);
PAINT PINK (-7890 5250);
DISPLAY INVISIBLE (-7890 5250);
FORCEPROP 1 LAST SCH_TITLE SKYLAKE - SKT0 - 7 OF 21
J 0
(-7950 50);
DISPLAY 1.212766 (-7950 50);
PAINT GREEN (-7950 50);
FORCEPROP 2 LAST PAGE_BORDER TRUE
J 0
(-7890 5250);
DISPLAY 0.851064 (-7890 5250);
PAINT PINK (-7890 5250);
DISPLAY INVISIBLE (-7890 5250);
FORCEPROP 2 LAST CDS_LIB mstr_symbols
J 0
(0 0);
PAINT ORANGE (0 0);
DISPLAY INVISIBLE (0 0);
FORCEPROP 1 LAST COMMENT_BODY TRUE
J 0
(12 12);
DISPLAY 0.638298 (12 12);
PAINT GREEN (12 12);
DISPLAY INVISIBLE (12 12);
FORCEPROP 2 LAST CDS_XR_PAGE_TITLE CR-27 : @BASEBOARD_FAB2_LIB.BASEBOARD_FAB2(SCH_1):PAGE27
J 0
(-7890 5250);
DISPLAY 0.638298 (-7890 5250);
PAINT PINK (-7890 5250);
DISPLAY INVISIBLE (-7890 5250);
WIRE 17 -1 (-2800 3825)(-2800 3875);
WIRE 17 -1 (-2800 3875)(-2800 3925);
WIRE 17 -1 (-2800 3925)(-2800 3975);
WIRE 17 -1 (-2800 3975)(-2800 4025);
WIRE 17 -1 (-2800 4025)(-2800 4075);
WIRE 17 -1 (-2800 4075)(-2800 4125);
WIRE 17 -1 (-2800 4125)(-2800 4175);
WIRE 17 -1 (-2800 4175)(-2800 4225);
WIRE 17 -1 (-2800 4225)(-2800 4275);
WIRE 17 -1 (-2800 4275)(-2800 4325);
WIRE 17 -1 (-2800 4325)(-2800 4375);
WIRE 17 -1 (-2800 4375)(-2800 4425);
WIRE 17 -1 (-2800 4425)(-2800 4475);
WIRE 17 -1 (-2800 4475)(-2800 4525);
WIRE 17 -1 (-2800 4525)(-2800 4575);
WIRE 17 -1 (-2050 4725)(-2800 4725);
FORCEPROP 2 LAST SIG_NAME M_E_DQS_DP<17:0>
J 0
(-2700 4735);
DISPLAY 0.617021 (-2700 4735);
PAINT ORANGE (-2700 4735);
WIRE 17 -1 (-2800 4675)(-2800 4725);
WIRE 17 -1 (-2800 4575)(-2800 4625);
WIRE 17 -1 (-2800 4625)(-2800 4675);
WIRE 17 -1 (-2800 2875)(-2800 2925);
WIRE 17 -1 (-2800 2925)(-2800 2975);
WIRE 17 -1 (-2800 2975)(-2800 3025);
WIRE 17 -1 (-2800 3025)(-2800 3075);
WIRE 17 -1 (-2800 3075)(-2800 3125);
WIRE 17 -1 (-2800 3125)(-2800 3175);
WIRE 17 -1 (-2800 3175)(-2800 3225);
WIRE 17 -1 (-2800 3225)(-2800 3275);
WIRE 17 -1 (-2800 3275)(-2800 3325);
WIRE 17 -1 (-2800 3325)(-2800 3375);
WIRE 17 -1 (-2800 3375)(-2800 3425);
WIRE 17 -1 (-2800 3425)(-2800 3475);
WIRE 17 -1 (-2800 3475)(-2800 3525);
WIRE 17 -1 (-2800 3525)(-2800 3575);
WIRE 17 -1 (-2800 3575)(-2800 3625);
WIRE 17 -1 (-2050 3750)(-2800 3750);
FORCEPROP 2 LAST SIG_NAME M_E_DQS_DN<17:0>
J 0
(-2700 3760);
DISPLAY 0.617021 (-2700 3760);
PAINT ORANGE (-2700 3760);
WIRE 17 -1 (-2800 3725)(-2800 3750);
WIRE 17 -1 (-2800 3625)(-2800 3675);
WIRE 17 -1 (-2800 3675)(-2800 3725);
WIRE 17 -1 (-2800 1925)(-2800 1975);
WIRE 17 -1 (-2800 1975)(-2800 2025);
WIRE 17 -1 (-2800 2025)(-2800 2075);
WIRE 17 -1 (-2800 2075)(-2800 2125);
WIRE 17 -1 (-2800 2125)(-2800 2175);
WIRE 17 -1 (-2800 2175)(-2800 2225);
WIRE 17 -1 (-2800 2225)(-2800 2275);
WIRE 17 -1 (-2800 2275)(-2800 2325);
WIRE 17 -1 (-2800 2325)(-2800 2375);
WIRE 17 -1 (-2800 2375)(-2800 2425);
WIRE 17 -1 (-2800 2425)(-2800 2475);
WIRE 17 -1 (-2800 2475)(-2800 2525);
WIRE 17 -1 (-2800 2525)(-2800 2575);
WIRE 17 -1 (-2800 2575)(-2800 2625);
WIRE 17 -1 (-2800 2625)(-2800 2675);
WIRE 17 -1 (-2050 2800)(-2800 2800);
FORCEPROP 2 LAST SIG_NAME M_E_MA<17:0>
J 0
(-2700 2810);
DISPLAY 0.617021 (-2700 2810);
PAINT ORANGE (-2700 2810);
WIRE 17 -1 (-2800 2775)(-2800 2800);
WIRE 17 -1 (-2800 2675)(-2800 2725);
WIRE 17 -1 (-2800 2725)(-2800 2775);
WIRE 17 -1 (-2050 800)(-2800 800);
FORCEPROP 2 LAST SIG_NAME M_E_BA<1:0>
J 0
(-2700 810);
DISPLAY 0.617021 (-2700 810);
PAINT ORANGE (-2700 810);
WIRE 17 -1 (-2800 725)(-2800 775);
WIRE 17 -1 (-2800 775)(-2800 800);
WIRE 17 -1 (-2050 900)(-2800 900);
FORCEPROP 2 LAST SIG_NAME M_E_BG<1:0>
J 0
(-2700 910);
DISPLAY 0.617021 (-2700 910);
PAINT ORANGE (-2700 910);
WIRE 17 -1 (-2800 875)(-2800 900);
WIRE 17 -1 (-2800 825)(-2800 875);
WIRE 17 -1 (-2800 1675)(-2800 1725);
WIRE 17 -1 (-2050 1850)(-2800 1850);
FORCEPROP 2 LAST SIG_NAME M_E_CKE<3:0>
J 0
(-2700 1860);
DISPLAY 0.617021 (-2700 1860);
PAINT ORANGE (-2700 1860);
WIRE 17 -1 (-2800 1825)(-2800 1850);
WIRE 17 -1 (-2800 1725)(-2800 1775);
WIRE 17 -1 (-2800 1775)(-2800 1825);
WIRE 17 -1 (-2800 975)(-2800 1025);
WIRE 17 -1 (-2800 1025)(-2800 1075);
WIRE 17 -1 (-2800 1075)(-2800 1125);
WIRE 17 -1 (-2800 1125)(-2800 1175);
WIRE 17 -1 (-2800 1175)(-2800 1225);
WIRE 17 -1 (-2050 1350)(-2800 1350);
FORCEPROP 2 LAST SIG_NAME M_E_CS_N<7:0>
J 0
(-2700 1360);
DISPLAY 0.617021 (-2700 1360);
PAINT ORANGE (-2700 1360);
WIRE 17 -1 (-2800 1325)(-2800 1350);
WIRE 17 -1 (-2800 1225)(-2800 1275);
WIRE 17 -1 (-2800 1275)(-2800 1325);
WIRE 17 -1 (-2800 1425)(-2800 1475);
WIRE 17 -1 (-2050 1600)(-2800 1600);
FORCEPROP 2 LAST SIG_NAME M_E_ODT<3:0>
J 0
(-2700 1610);
DISPLAY 0.617021 (-2700 1610);
PAINT ORANGE (-2700 1610);
WIRE 17 -1 (-2800 1575)(-2800 1600);
WIRE 17 -1 (-2800 1475)(-2800 1525);
WIRE 17 -1 (-2800 1525)(-2800 1575);
WIRE 17 -1 (-5625 1525)(-5625 1575);
WIRE 17 -1 (-5625 1575)(-5625 1625);
WIRE 17 -1 (-5625 1625)(-5625 1675);
WIRE 17 -1 (-5625 1675)(-5625 1725);
WIRE 17 -1 (-5625 1725)(-5625 1775);
WIRE 17 -1 (-5625 1775)(-5625 1825);
WIRE 17 -1 (-5625 1825)(-5625 1875);
WIRE 17 -1 (-5625 1875)(-5625 1925);
WIRE 17 -1 (-5625 1925)(-5625 1975);
WIRE 17 -1 (-5625 1975)(-5625 2025);
WIRE 17 -1 (-5625 2025)(-5625 2075);
WIRE 17 -1 (-5625 2075)(-5625 2125);
WIRE 17 -1 (-5625 2125)(-5625 2175);
WIRE 17 -1 (-5625 2175)(-5625 2225);
WIRE 17 -1 (-5625 2225)(-5625 2275);
WIRE 17 -1 (-5625 2275)(-5625 2325);
WIRE 17 -1 (-5625 2325)(-5625 2375);
WIRE 17 -1 (-5625 2375)(-5625 2425);
WIRE 17 -1 (-5625 2425)(-5625 2475);
WIRE 17 -1 (-5625 2475)(-5625 2525);
WIRE 17 -1 (-5625 2525)(-5625 2575);
WIRE 17 -1 (-5625 2575)(-5625 2625);
WIRE 17 -1 (-5625 2625)(-5625 2675);
WIRE 17 -1 (-5625 2675)(-5625 2725);
WIRE 17 -1 (-5625 2725)(-5625 2775);
WIRE 17 -1 (-5625 2775)(-5625 2825);
WIRE 17 -1 (-5625 2825)(-5625 2875);
WIRE 17 -1 (-5625 2875)(-5625 2925);
WIRE 17 -1 (-5625 2925)(-5625 2975);
WIRE 17 -1 (-5625 2975)(-5625 3025);
WIRE 17 -1 (-5625 3025)(-5625 3075);
WIRE 17 -1 (-5625 3075)(-5625 3125);
WIRE 17 -1 (-5625 3125)(-5625 3175);
WIRE 17 -1 (-5625 3175)(-5625 3225);
WIRE 17 -1 (-5625 3225)(-5625 3275);
WIRE 17 -1 (-5625 3275)(-5625 3325);
WIRE 17 -1 (-5625 3325)(-5625 3375);
WIRE 17 -1 (-5625 3375)(-5625 3425);
WIRE 17 -1 (-5625 3425)(-5625 3475);
WIRE 17 -1 (-5625 3475)(-5625 3525);
WIRE 17 -1 (-5625 3525)(-5625 3575);
WIRE 17 -1 (-5625 3575)(-5625 3625);
WIRE 17 -1 (-5625 3625)(-5625 3675);
WIRE 17 -1 (-5625 3675)(-5625 3725);
WIRE 17 -1 (-5625 3725)(-5625 3775);
WIRE 17 -1 (-5625 3775)(-5625 3825);
WIRE 17 -1 (-5625 3825)(-5625 3875);
WIRE 17 -1 (-5625 3875)(-5625 3925);
WIRE 17 -1 (-5625 3925)(-5625 3975);
WIRE 17 -1 (-5625 3975)(-5625 4025);
WIRE 17 -1 (-5625 4025)(-5625 4075);
WIRE 17 -1 (-5625 4075)(-5625 4125);
WIRE 17 -1 (-5625 4125)(-5625 4175);
WIRE 17 -1 (-5625 4175)(-5625 4225);
WIRE 17 -1 (-5625 4225)(-5625 4275);
WIRE 17 -1 (-5625 4275)(-5625 4325);
WIRE 17 -1 (-5625 4325)(-5625 4375);
WIRE 17 -1 (-5625 4375)(-5625 4425);
WIRE 17 -1 (-5625 4425)(-5625 4475);
WIRE 17 -1 (-5625 4475)(-5625 4525);
WIRE 17 -1 (-5625 4525)(-5625 4575);
WIRE 17 -1 (-5625 4775)(-6375 4775);
FORCEPROP 2 LAST SIG_NAME M_E_DQ<63:0>
J 0
(-6325 4785);
DISPLAY 0.617021 (-6325 4785);
PAINT ORANGE (-6325 4785);
WIRE 17 -1 (-5625 4675)(-5625 4775);
WIRE 17 -1 (-5625 4575)(-5625 4625);
WIRE 17 -1 (-5625 4625)(-5625 4675);
WIRE 17 -1 (-5625 625)(-5625 675);
WIRE 17 -1 (-5625 800)(-6375 800);
FORCEPROP 2 LAST SIG_NAME M_E_CLK_DN<3:0>
J 0
(-6325 810);
DISPLAY 0.617021 (-6325 810);
PAINT ORANGE (-6325 810);
WIRE 17 -1 (-5625 775)(-5625 800);
WIRE 17 -1 (-5625 675)(-5625 725);
WIRE 17 -1 (-5625 725)(-5625 775);
WIRE 17 -1 (-5625 825)(-5625 875);
WIRE 17 -1 (-5625 1000)(-6375 1000);
FORCEPROP 2 LAST SIG_NAME M_E_CLK_DP<3:0>
J 0
(-6325 1010);
DISPLAY 0.617021 (-6325 1010);
PAINT ORANGE (-6325 1010);
WIRE 17 -1 (-5625 975)(-5625 1000);
WIRE 17 -1 (-5625 875)(-5625 925);
WIRE 17 -1 (-5625 925)(-5625 975);
WIRE 17 -1 (-5625 1075)(-5625 1125);
WIRE 17 -1 (-5625 1125)(-5625 1175);
WIRE 17 -1 (-5625 1175)(-5625 1225);
WIRE 17 -1 (-5625 1225)(-5625 1275);
WIRE 17 -1 (-5625 1275)(-5625 1325);
WIRE 17 -1 (-5625 1450)(-6375 1450);
FORCEPROP 2 LAST SIG_NAME M_E_ECC<7:0>
J 0
(-6325 1460);
DISPLAY 0.617021 (-6325 1460);
PAINT ORANGE (-6325 1460);
WIRE 17 -1 (-5625 1425)(-5625 1450);
WIRE 17 -1 (-5625 1325)(-5625 1375);
WIRE 17 -1 (-5625 1375)(-5625 1425);
WIRE 16 -1 (-5025 4250)(-5525 4250);
WIRE 16 -1 (-5525 3550)(-5025 3550);
WIRE 16 -1 (-3325 3900)(-2900 3900);
WIRE 16 -1 (-5025 4150)(-5525 4150);
WIRE 16 -1 (-3325 1550)(-2900 1550);
WIRE 16 -1 (-5525 3250)(-5025 3250);
WIRE 16 -1 (-5525 3150)(-5025 3150);
WIRE 16 -1 (-5525 3400)(-5025 3400);
WIRE 16 -1 (-5025 4400)(-5525 4400);
WIRE 16 -1 (-5525 1750)(-5025 1750);
WIRE 16 -1 (-6400 500)(-5025 500);
FORCEPROP 2 LAST SIG_NAME M_E_C<2>
J 0
(-6350 510);
DISPLAY 0.617021 (-6350 510);
PAINT ORANGE (-6350 510);
WIRE 16 -1 (-5025 1050)(-5525 1050);
WIRE 16 -1 (-5025 1100)(-5525 1100);
WIRE 16 -1 (-5025 1150)(-5525 1150);
WIRE 16 -1 (-5025 1200)(-5525 1200);
WIRE 16 -1 (-5025 1250)(-5525 1250);
WIRE 16 -1 (-5025 1300)(-5525 1300);
WIRE 16 -1 (-5025 1350)(-5525 1350);
WIRE 16 -1 (-5025 1400)(-5525 1400);
WIRE 16 -1 (-5525 1500)(-5025 1500);
WIRE 16 -1 (-5525 1550)(-5025 1550);
WIRE 16 -1 (-5525 1600)(-5025 1600);
WIRE 16 -1 (-5025 1650)(-5525 1650);
WIRE 16 -1 (-5525 1700)(-5025 1700);
WIRE 16 -1 (-5025 1800)(-5525 1800);
WIRE 16 -1 (-5525 1850)(-5025 1850);
WIRE 16 -1 (-5525 1900)(-5025 1900);
WIRE 16 -1 (-5525 1950)(-5025 1950);
WIRE 16 -1 (-5525 2000)(-5025 2000);
WIRE 16 -1 (-5025 800)(-5525 800);
WIRE 16 -1 (-5025 850)(-5525 850);
WIRE 16 -1 (-5025 900)(-5525 900);
WIRE 16 -1 (-5025 950)(-5525 950);
WIRE 16 -1 (-5025 600)(-5525 600);
WIRE 16 -1 (-5025 650)(-5525 650);
WIRE 16 -1 (-5025 700)(-5525 700);
WIRE 16 -1 (-5025 750)(-5525 750);
WIRE 16 -1 (-5525 2050)(-5025 2050);
WIRE 16 -1 (-5525 2100)(-5025 2100);
WIRE 16 -1 (-5525 2150)(-5025 2150);
WIRE 16 -1 (-5525 2200)(-5025 2200);
WIRE 16 -1 (-5025 2250)(-5525 2250);
WIRE 16 -1 (-5525 2300)(-5025 2300);
WIRE 16 -1 (-5525 2350)(-5025 2350);
WIRE 16 -1 (-5025 2400)(-5525 2400);
WIRE 16 -1 (-5525 2450)(-5025 2450);
WIRE 16 -1 (-5525 2500)(-5025 2500);
WIRE 16 -1 (-5525 2550)(-5025 2550);
WIRE 16 -1 (-5525 2600)(-5025 2600);
WIRE 16 -1 (-5025 2650)(-5525 2650);
WIRE 16 -1 (-5525 2700)(-5025 2700);
WIRE 16 -1 (-5525 2750)(-5025 2750);
WIRE 16 -1 (-5525 2800)(-5025 2800);
WIRE 16 -1 (-5525 2850)(-5025 2850);
WIRE 16 -1 (-5525 2900)(-5025 2900);
WIRE 16 -1 (-5525 2950)(-5025 2950);
WIRE 16 -1 (-5025 3000)(-5525 3000);
WIRE 16 -1 (-5525 3050)(-5025 3050);
WIRE 16 -1 (-5525 3100)(-5025 3100);
WIRE 16 -1 (-5525 3200)(-5025 3200);
WIRE 16 -1 (-5525 3300)(-5025 3300);
WIRE 16 -1 (-5025 3350)(-5525 3350);
WIRE 16 -1 (-5525 3450)(-5025 3450);
WIRE 16 -1 (-5025 3500)(-5525 3500);
WIRE 16 -1 (-5525 3600)(-5025 3600);
WIRE 16 -1 (-5025 3650)(-5525 3650);
WIRE 16 -1 (-5025 3700)(-5525 3700);
WIRE 16 -1 (-5025 3750)(-5525 3750);
WIRE 16 -1 (-5025 3800)(-5525 3800);
WIRE 16 -1 (-5025 3850)(-5525 3850);
WIRE 16 -1 (-5025 3900)(-5525 3900);
WIRE 16 -1 (-5025 3950)(-5525 3950);
WIRE 16 -1 (-5025 4000)(-5525 4000);
WIRE 16 -1 (-5025 4050)(-5525 4050);
WIRE 16 -1 (-5025 4100)(-5525 4100);
WIRE 16 -1 (-5025 4200)(-5525 4200);
WIRE 16 -1 (-5025 4300)(-5525 4300);
WIRE 16 -1 (-5025 4350)(-5525 4350);
WIRE 16 -1 (-5025 4450)(-5525 4450);
WIRE 16 -1 (-5025 4500)(-5525 4500);
WIRE 16 -1 (-5025 4550)(-5525 4550);
WIRE 16 -1 (-5025 4600)(-5525 4600);
WIRE 16 -1 (-5025 4650)(-5525 4650);
WIRE 16 -1 (-3325 1400)(-2900 1400);
WIRE 16 -1 (-3325 1450)(-2900 1450);
WIRE 16 -1 (-3325 1500)(-2900 1500);
WIRE 16 -1 (-3325 1900)(-2900 1900);
WIRE 16 -1 (-3325 1950)(-2900 1950);
WIRE 16 -1 (-3325 2000)(-2900 2000);
WIRE 16 -1 (-3325 950)(-2900 950);
WIRE 16 -1 (-3325 1000)(-2900 1000);
WIRE 16 -1 (-3325 1050)(-2900 1050);
WIRE 16 -1 (-3325 1100)(-2900 1100);
WIRE 16 -1 (-3325 1150)(-2900 1150);
WIRE 16 -1 (-3325 1200)(-2900 1200);
WIRE 16 -1 (-3325 1250)(-2900 1250);
WIRE 16 -1 (-3325 1300)(-2900 1300);
WIRE 16 -1 (-3325 1650)(-2900 1650);
WIRE 16 -1 (-3325 1700)(-2900 1700);
WIRE 16 -1 (-3325 1750)(-2900 1750);
WIRE 16 -1 (-3325 1800)(-2900 1800);
WIRE 16 -1 (-3325 800)(-2900 800);
WIRE 16 -1 (-3325 850)(-2900 850);
WIRE 16 -1 (-3325 700)(-2900 700);
WIRE 16 -1 (-3325 750)(-2900 750);
WIRE 16 -1 (-3325 550)(-2050 550);
FORCEPROP 2 LAST SIG_NAME M_E_ALERT_N
J 0
(-2700 560);
DISPLAY 0.617021 (-2700 560);
PAINT ORANGE (-2700 560);
WIRE 16 -1 (-3325 500)(-2050 500);
FORCEPROP 2 LAST SIG_NAME M_E_PAR
J 0
(-2700 510);
DISPLAY 0.617021 (-2700 510);
PAINT ORANGE (-2700 510);
WIRE 16 -1 (-3325 600)(-2050 600);
FORCEPROP 2 LAST SIG_NAME M_E_ACT_N
J 0
(-2700 610);
DISPLAY 0.617021 (-2700 610);
PAINT ORANGE (-2700 610);
WIRE 16 -1 (-3325 2050)(-2900 2050);
WIRE 16 -1 (-3325 2100)(-2900 2100);
WIRE 16 -1 (-3325 2150)(-2900 2150);
WIRE 16 -1 (-3325 2200)(-2900 2200);
WIRE 16 -1 (-3325 2250)(-2900 2250);
WIRE 16 -1 (-3325 2300)(-2900 2300);
WIRE 16 -1 (-3325 2350)(-2900 2350);
WIRE 16 -1 (-3325 2400)(-2900 2400);
WIRE 16 -1 (-3325 2450)(-2900 2450);
WIRE 16 -1 (-3325 2500)(-2900 2500);
WIRE 16 -1 (-3325 2550)(-2900 2550);
WIRE 16 -1 (-3325 2600)(-2900 2600);
WIRE 16 -1 (-3325 2650)(-2900 2650);
WIRE 16 -1 (-3325 2700)(-2900 2700);
WIRE 16 -1 (-3325 2750)(-2900 2750);
WIRE 16 -1 (-3325 3800)(-2900 3800);
WIRE 16 -1 (-3325 3850)(-2900 3850);
WIRE 16 -1 (-3325 3950)(-2900 3950);
WIRE 16 -1 (-3325 4000)(-2900 4000);
WIRE 16 -1 (-3325 4050)(-2900 4050);
WIRE 16 -1 (-3325 2850)(-2900 2850);
WIRE 16 -1 (-3325 2900)(-2900 2900);
WIRE 16 -1 (-3325 2950)(-2900 2950);
WIRE 16 -1 (-3325 3000)(-2900 3000);
WIRE 16 -1 (-3325 3050)(-2900 3050);
WIRE 16 -1 (-3325 3100)(-2900 3100);
WIRE 16 -1 (-3325 3150)(-2900 3150);
WIRE 16 -1 (-3325 3200)(-2900 3200);
WIRE 16 -1 (-3325 3250)(-2900 3250);
WIRE 16 -1 (-3325 3300)(-2900 3300);
WIRE 16 -1 (-3325 3350)(-2900 3350);
WIRE 16 -1 (-3325 3400)(-2900 3400);
WIRE 16 -1 (-3325 3450)(-2900 3450);
WIRE 16 -1 (-3325 3500)(-2900 3500);
WIRE 16 -1 (-3325 3550)(-2900 3550);
WIRE 16 -1 (-3325 3600)(-2900 3600);
WIRE 16 -1 (-3325 3650)(-2900 3650);
WIRE 16 -1 (-3325 3700)(-2900 3700);
WIRE 16 -1 (-3325 4100)(-2900 4100);
WIRE 16 -1 (-3325 4150)(-2900 4150);
WIRE 16 -1 (-3325 4200)(-2900 4200);
WIRE 16 -1 (-3325 4250)(-2900 4250);
WIRE 16 -1 (-3325 4300)(-2900 4300);
WIRE 16 -1 (-3325 4350)(-2900 4350);
WIRE 16 -1 (-3325 4400)(-2900 4400);
WIRE 16 -1 (-3325 4450)(-2900 4450);
WIRE 16 -1 (-3325 4500)(-2900 4500);
WIRE 16 -1 (-3325 4550)(-2900 4550);
WIRE 16 -1 (-3325 4600)(-2900 4600);
WIRE 16 -1 (-3325 4650)(-2900 4650);
FORCENOTE
SKYLAKE - SKT0 - 7 OF 21
(-1650 150) 0;
DISPLAY LEFT (-1650 150);
DISPLAY 1.021277 (-1650 150);
PAINT RED (-1650 150);
FORCENOTE
ROOM=CPU0
(-7925 350) 0;
DISPLAY LEFT (-7925 350);
DISPLAY 1.382979 (-7925 350);
PAINT PURPLE (-7925 350);
FORCENOTE
BOM_COST=PROC_SOCKET
(-7925 225) 0;
DISPLAY LEFT (-7925 225);
DISPLAY 1.382979 (-7925 225);
PAINT PURPLE (-7925 225);
FORCENOTE
. 
(50 50) 0;
DISPLAY LEFT (50 50);
DISPLAY 1.021277 (50 50);
PAINT PURPLE (50 50);
QUIT
